FILE_TYPE = MACRO_DRAWING;
SET COLOR_WIRE YELLOW;
SET COLOR_PROP MONO;
SET COLOR_DOT WHITE;
SET COLOR_ARC YELLOW;
SET COLOR_BODY GREEN;
SET COLOR_NOTE MONO;
SET PROP_DISPLAY VALUE;
SET PAGE_NUMBER P239;
FORCEADD RES..2
(10350 3075);
FORCEPROP 1 LASTPIN (10350 3175) $PN 1
J 0
(10355 3137);
DISPLAY 0.617021 (10355 3137);
PAINT ORANGE (10355 3137);
FORCEPROP 1 LASTPIN (10350 2975) $PN 2
J 0
(10355 2985);
DISPLAY 0.617021 (10355 2985);
PAINT ORANGE (10355 2985);
FORCEPROP 1 LAST TOLERANCE 1%
J 0
(10445 3100);
DISPLAY 0.617021 (10445 3100);
PAINT SKYBLUE (10445 3100);
FORCEPROP 1 LAST VALUE 10.0K
J 0
(10445 3150);
DISPLAY 0.617021 (10445 3150);
PAINT SKYBLUE (10445 3150);
FORCEPROP 1 LAST LOCATION R9F32
J 0
(10445 3200);
DISPLAY 0.617021 (10445 3200);
PAINT AQUA (10445 3200);
FORCEPROP 1 LAST PACK_TYPE 0402
J 0
(10440 2950);
DISPLAY 0.617021 (10440 2950);
PAINT SKYBLUE (10440 2950);
FORCEPROP 1 LAST WATTAGE 1/16W
J 0
(10440 3050);
DISPLAY 0.617021 (10440 3050);
PAINT SKYBLUE (10440 3050);
FORCEPROP 1 LAST PART_NUMBER G21796-016
R 1
J 0
(10415 2950);
DISPLAY 0.617021 (10415 2950);
PAINT BLUE (10415 2950);
FORCEPROP 1 LAST MATERIAL CHIP
J 0
(10440 3000);
DISPLAY 0.617021 (10440 3000);
PAINT SKYBLUE (10440 3000);
FORCEPROP 1 LAST PATH I100
J 0
(10400 3250);
DISPLAY 0.978723 (10400 3250);
PAINT WHITE (10400 3250);
DISPLAY INVISIBLE (10400 3250);
FORCEPROP 2 LAST ROOM CPU0
J 0
(10375 2850);
PAINT WHITE (10375 2850);
DISPLAY INVISIBLE (10375 2850);
FORCEPROP 2 LAST BOM_COST PROC_SIDEBAND
J 0
(10350 3075);
PAINT WHITE (10350 3075);
DISPLAY INVISIBLE (10350 3075);
FORCEPROP 2 LAST CDS_LIB mstr_discrete
J 2
(10350 3075);
PAINT ORANGE (10350 3075);
DISPLAY INVISIBLE (10350 3075);
FORCEPROP 2 LAST SEC_TYPE 0402
J 0
(10400 3300);
DISPLAY 1.021277 (10400 3300);
PAINT ORANGE (10400 3300);
DISPLAY INVISIBLE (10400 3300);
FORCEPROP 2 LAST SEC 1
J 0
(10400 3300);
DISPLAY 0.680851 (10400 3300);
PAINT MONO (10400 3300);
DISPLAY INVISIBLE (10400 3300);
FORCEPROP 2 LAST CDS_LOCATION R9F32
J 0
(10395 3200);
DISPLAY 0.617021 (10395 3200);
PAINT AQUA (10395 3200);
DISPLAY INVISIBLE (10395 3200);
FORCEADD RES..2
(9925 800);
FORCEPROP 1 LAST PACK_TYPE 0402
J 0
(10015 675);
DISPLAY 0.617021 (10015 675);
PAINT SKYBLUE (10015 675);
FORCEPROP 1 LASTPIN (9925 700) $PN 2
J 0
(9930 710);
DISPLAY 0.617021 (9930 710);
PAINT ORANGE (9930 710);
FORCEPROP 1 LAST LOCATION R9W32
J 0
(10020 925);
DISPLAY 0.617021 (10020 925);
PAINT AQUA (10020 925);
FORCEPROP 1 LAST VALUE 10.0K
J 0
(10020 875);
DISPLAY 0.617021 (10020 875);
PAINT SKYBLUE (10020 875);
FORCEPROP 1 LASTPIN (9925 900) $PN 1
J 0
(9930 862);
DISPLAY 0.617021 (9930 862);
PAINT ORANGE (9930 862);
FORCEPROP 1 LAST PART_NUMBER G21796-016
R 1
J 0
(9990 675);
DISPLAY 0.617021 (9990 675);
PAINT BLUE (9990 675);
FORCEPROP 1 LAST TOLERANCE 1%
J 0
(10020 825);
DISPLAY 0.617021 (10020 825);
PAINT SKYBLUE (10020 825);
FORCEPROP 1 LAST WATTAGE 1/16W
J 0
(10015 775);
DISPLAY 0.617021 (10015 775);
PAINT SKYBLUE (10015 775);
FORCEPROP 1 LAST MATERIAL CHIP
J 0
(10015 725);
DISPLAY 0.617021 (10015 725);
PAINT SKYBLUE (10015 725);
FORCEPROP 1 LAST PATH I101
J 0
(9975 975);
DISPLAY 0.978723 (9975 975);
PAINT WHITE (9975 975);
DISPLAY INVISIBLE (9975 975);
FORCEPROP 2 LAST SEC 1
J 0
(9975 1025);
DISPLAY 0.680851 (9975 1025);
PAINT MONO (9975 1025);
DISPLAY INVISIBLE (9975 1025);
FORCEPROP 2 LAST SEC_TYPE 0402
J 0
(9975 1025);
DISPLAY 1.021277 (9975 1025);
PAINT ORANGE (9975 1025);
DISPLAY INVISIBLE (9975 1025);
FORCEPROP 2 LAST CDS_LIB mstr_discrete
J 2
(9925 800);
PAINT ORANGE (9925 800);
DISPLAY INVISIBLE (9925 800);
FORCEPROP 2 LAST BOM_COST PROC_SIDEBAND
J 0
(9925 800);
PAINT WHITE (9925 800);
DISPLAY INVISIBLE (9925 800);
FORCEPROP 2 LAST ROOM CPU0
J 0
(9950 575);
PAINT WHITE (9950 575);
DISPLAY INVISIBLE (9950 575);
FORCEPROP 2 LAST CDS_LOCATION R9W32
J 0
(9970 925);
DISPLAY 0.617021 (9970 925);
PAINT AQUA (9970 925);
DISPLAY INVISIBLE (9970 925);
FORCEADD 21K5R2F-GP..1
(9925 1325);
FORCEPROP 1 LAST VALUE 21K5R2F-GP
J 0
(9975 1370);
DISPLAY 0.617021 (9975 1370);
PAINT GREEN (9975 1370);
FORCEPROP 1 LAST LOCATION R9W31
J 0
(9975 1430);
DISPLAY 0.617021 (9975 1430);
PAINT GREEN (9975 1430);
FORCEPROP 2 LAST TOLERANCE 1%
J 0
(9975 1275);
DISPLAY 0.638298 (9975 1275);
PAINT GREEN (9975 1275);
FORCEPROP 2 LASTPIN (9925 1200) $PN 2
R 1
J 2
(9915 1190);
DISPLAY 0.808511 (9915 1190);
PAINT ORANGE (9915 1190);
FORCEPROP 2 LASTPIN (9925 1450) $PN 1
R 1
J 0
(9915 1460);
DISPLAY 0.808511 (9915 1460);
PAINT ORANGE (9915 1460);
FORCEPROP 2 LAST ATTRIBUTE 21.5KOHM
J 0
(9975 1325);
DISPLAY 0.638298 (9975 1325);
PAINT GREEN (9975 1325);
FORCEPROP 2 LAST PACK_SIZE 0402
J 0
(9975 1175);
DISPLAY 0.638298 (9975 1175);
PAINT GREEN (9975 1175);
FORCEPROP 2 LAST RATED 1/16W
J 0
(9975 1225);
DISPLAY 0.638298 (9975 1225);
PAINT GREEN (9975 1225);
FORCEPROP 1 LAST PACK_TYPE RCL_GP
J 0
(9925 1325);
DISPLAY 0.617021 (9925 1325);
PAINT GREEN (9925 1325);
DISPLAY INVISIBLE (9925 1325);
FORCEPROP 2 LAST SEC 1
J 0
(9950 1450);
DISPLAY 0.680851 (9950 1450);
PAINT MONO (9950 1450);
DISPLAY INVISIBLE (9950 1450);
FORCEPROP 2 LAST SEC_TYPE RCL_GP
J 0
(9950 1450);
DISPLAY 1.021277 (9950 1450);
PAINT ORANGE (9950 1450);
DISPLAY INVISIBLE (9950 1450);
FORCEPROP 1 LAST PART_NUMBER 64.21525.6DL
J 0
(9925 1325);
DISPLAY 0.617021 (9925 1325);
PAINT GREEN (9925 1325);
DISPLAY INVISIBLE (9925 1325);
FORCEPROP 2 LAST CDS_LIB w_hdl
J 0
(9925 1325);
DISPLAY INVISIBLE (9925 1325);
FORCEPROP 1 LAST PATH I102
J 0
(9925 1325);
DISPLAY 0.617021 (9925 1325);
PAINT GREEN (9925 1325);
DISPLAY INVISIBLE (9925 1325);
FORCEPROP 1 LAST CDS_LMAN_SYM_OUTLINE -50,75,50,-75
J 0
(9925 1325);
DISPLAY 0.468085 (9925 1325);
PAINT GREEN (9925 1325);
DISPLAY INVISIBLE (9925 1325);
FORCEADD CAP..1
(6550 4250);
FORCEPROP 1 LAST PART_NUMBER E15431-002
J 0
(6600 4100);
DISPLAY 0.617021 (6600 4100);
PAINT BLUE (6600 4100);
FORCEPROP 1 LAST TOLERANCE 20%
J 0
(6600 4200);
DISPLAY 0.617021 (6600 4200);
PAINT SKYBLUE (6600 4200);
FORCEPROP 1 LAST MATERIAL X6S
J 0
(6600 4150);
DISPLAY 0.617021 (6600 4150);
PAINT SKYBLUE (6600 4150);
FORCEPROP 1 LAST PACK_TYPE 0603
J 0
(6600 4050);
DISPLAY 0.617021 (6600 4050);
PAINT SKYBLUE (6600 4050);
FORCEPROP 1 LAST LOCATION C9W17
J 0
(6600 4350);
DISPLAY 0.617021 (6600 4350);
PAINT AQUA (6600 4350);
FORCEPROP 1 LASTPIN (6550 4350) $PN 1
J 0
(6560 4330);
DISPLAY 0.617021 (6560 4330);
PAINT WHITE (6560 4330);
FORCEPROP 1 LAST VOLTAGE 6.3V
J 0
(6600 4250);
DISPLAY 0.617021 (6600 4250);
PAINT SKYBLUE (6600 4250);
FORCEPROP 1 LASTPIN (6550 4150) $PN 2
J 0
(6560 4130);
DISPLAY 0.617021 (6560 4130);
PAINT WHITE (6560 4130);
FORCEPROP 0 LAST POP NOPOP
J 0
(6600 4000);
DISPLAY 0.638298 (6600 4000);
PAINT RED (6600 4000);
FORCEPROP 1 LAST VALUE 10UF
J 0
(6600 4300);
DISPLAY 0.617021 (6600 4300);
PAINT SKYBLUE (6600 4300);
FORCEPROP 2 LAST CDS_LOCATION C9W17
J 0
(6600 4350);
DISPLAY 0.617021 (6600 4350);
PAINT AQUA (6600 4350);
DISPLAY INVISIBLE (6600 4350);
FORCEPROP 0 LAST CDS_SEC 1
J 0
(6600 4400);
DISPLAY INVISIBLE (6600 4400);
FORCEPROP 2 LAST SEC 1
J 0
(6600 4450);
DISPLAY 1.106383 (6600 4450);
PAINT MONO (6600 4450);
DISPLAY INVISIBLE (6600 4450);
FORCEPROP 2 LAST SEC_TYPE 0603
J 0
(6600 4450);
DISPLAY 1.659574 (6600 4450);
PAINT ORANGE (6600 4450);
DISPLAY INVISIBLE (6600 4450);
FORCEPROP 2 LAST ROOM P1V26_BMC_STBY_VR
J 0
(6600 4400);
DISPLAY 0.723404 (6600 4400);
PAINT GREEN (6600 4400);
DISPLAY INVISIBLE (6600 4400);
FORCEPROP 2 LAST BOM_COST P1V26_BMC_STBY_VR
J 0
(6425 4400);
PAINT WHITE (6425 4400);
DISPLAY INVISIBLE (6425 4400);
FORCEPROP 2 LAST CDS_LIB mstr_discrete
J 0
(6550 4250);
PAINT ORANGE (6550 4250);
DISPLAY INVISIBLE (6550 4250);
FORCEPROP 1 LAST PATH I104
J 0
(6600 4400);
DISPLAY 0.978723 (6600 4400);
PAINT WHITE (6600 4400);
DISPLAY INVISIBLE (6600 4400);
FORCEADD GND..1
(6550 4025);
FORCEPROP 3 LASTPIN (6550 4075) SIG_NAME GND\g
J 0
(6560 4085);
DISPLAY 0.659574 (6560 4085);
PAINT MONO (6560 4085);
DISPLAY INVISIBLE (6560 4085);
FORCEPROP 1 LAST PATH I105
J 0
(6625 4025);
DISPLAY 0.872340 (6625 4025);
PAINT AQUA (6625 4025);
DISPLAY INVISIBLE (6625 4025);
FORCEPROP 2 LAST CDS_LIB mstr_symbols
J 0
(6550 4025);
PAINT ORANGE (6550 4025);
DISPLAY INVISIBLE (6550 4025);
FORCEPROP 1 LAST SIZE 1B
J 0
(6625 3975);
DISPLAY 0.872340 (6625 3975);
PAINT AQUA (6625 3975);
DISPLAY INVISIBLE (6625 3975);
FORCEPROP 1 LAST VOLTAGE 0.0V
J 0
(6505 3982);
DISPLAY 0.340426 (6505 3982);
PAINT SKYBLUE (6505 3982);
DISPLAY INVISIBLE (6505 3982);
FORCEPROP 1 LAST BODY_TYPE PLUMBING
J 0
(6505 3982);
DISPLAY 0.340426 (6505 3982);
PAINT GREEN (6505 3982);
DISPLAY INVISIBLE (6505 3982);
FORCEPROP 1 LAST HDL_POWER GND
J 0
(6550 4175);
DISPLAY 0.872340 (6550 4175);
PAINT GREEN (6550 4175);
DISPLAY INVISIBLE (6550 4175);
FORCEADD CAP_A..1
(11250 3650);
FORCEPROP 1 LAST LOCATION C9W19
J 0
(11300 3750);
DISPLAY 0.617021 (11300 3750);
PAINT AQUA (11300 3750);
FORCEPROP 0 LAST POP NOPOP
J 0
(11300 3400);
DISPLAY 0.638298 (11300 3400);
PAINT RED (11300 3400);
FORCEPROP 1 LAST PART_NUMBER E15431-004
J 0
(11300 3500);
DISPLAY 0.617021 (11300 3500);
PAINT BLUE (11300 3500);
FORCEPROP 1 LAST PACK_TYPE 0603V
J 0
(11300 3450);
DISPLAY 0.617021 (11300 3450);
PAINT SKYBLUE (11300 3450);
FORCEPROP 1 LASTPIN (11250 3750) $PN 1
J 0
(11260 3730);
DISPLAY 0.617021 (11260 3730);
PAINT GREEN (11260 3730);
FORCEPROP 1 LAST MATERIAL X6S
J 0
(11300 3550);
DISPLAY 0.617021 (11300 3550);
PAINT SKYBLUE (11300 3550);
FORCEPROP 1 LAST TOLERANCE 20%
J 0
(11300 3600);
DISPLAY 0.617021 (11300 3600);
PAINT SKYBLUE (11300 3600);
FORCEPROP 1 LASTPIN (11250 3550) $PN 2
J 0
(11260 3530);
DISPLAY 0.617021 (11260 3530);
PAINT GREEN (11260 3530);
FORCEPROP 1 LAST VOLTAGE 4V
J 0
(11300 3650);
DISPLAY 0.617021 (11300 3650);
PAINT SKYBLUE (11300 3650);
FORCEPROP 1 LAST VALUE 22.0UF
J 0
(11300 3700);
DISPLAY 0.617021 (11300 3700);
PAINT SKYBLUE (11300 3700);
FORCEPROP 2 LAST CDS_LOCATION C9W19
J 0
(11300 3750);
DISPLAY 0.617021 (11300 3750);
PAINT AQUA (11300 3750);
DISPLAY INVISIBLE (11300 3750);
FORCEPROP 2 LAST ROOM PVCCIN_CPU0_DECAP_VR
J 0
(11300 3800);
DISPLAY 1.021277 (11300 3800);
PAINT ORANGE (11300 3800);
DISPLAY INVISIBLE (11300 3800);
FORCEPROP 2 LAST $SEC 1
J 0
(11300 3850);
PAINT MONO (11300 3850);
DISPLAY INVISIBLE (11300 3850);
FORCEPROP 2 LAST CDS_SEC 1
J 0
(11300 3850);
PAINT MONO (11300 3850);
DISPLAY INVISIBLE (11300 3850);
FORCEPROP 2 LAST CDS_LIB dev_discrete
J 0
(11250 3650);
PAINT ORANGE (11250 3650);
DISPLAY INVISIBLE (11250 3650);
FORCEPROP 2 LAST BOM_COST PROC_SOCKET
J 0
(11300 3850);
DISPLAY 1.021277 (11300 3850);
PAINT ORANGE (11300 3850);
DISPLAY INVISIBLE (11300 3850);
FORCEPROP 1 LAST PATH I111
J 0
(11300 3800);
DISPLAY 0.978723 (11300 3800);
PAINT WHITE (11300 3800);
DISPLAY INVISIBLE (11300 3800);
FORCEADD CAP..1
(10875 3625);
FORCEPROP 1 LAST VOLTAGE 6.3V
J 0
(10925 3625);
DISPLAY 0.617021 (10925 3625);
PAINT SKYBLUE (10925 3625);
FORCEPROP 1 LAST TOLERANCE 20%
J 0
(10925 3575);
DISPLAY 0.617021 (10925 3575);
PAINT SKYBLUE (10925 3575);
FORCEPROP 1 LAST MATERIAL X6S
J 0
(10925 3525);
DISPLAY 0.617021 (10925 3525);
PAINT SKYBLUE (10925 3525);
FORCEPROP 1 LAST PACK_TYPE 0603
J 0
(10925 3425);
DISPLAY 0.617021 (10925 3425);
PAINT SKYBLUE (10925 3425);
FORCEPROP 1 LAST PART_NUMBER E15431-002
J 0
(10925 3475);
DISPLAY 0.617021 (10925 3475);
PAINT BLUE (10925 3475);
FORCEPROP 1 LASTPIN (10875 3525) $PN 2
J 0
(10885 3505);
DISPLAY 0.617021 (10885 3505);
PAINT WHITE (10885 3505);
FORCEPROP 1 LASTPIN (10875 3725) $PN 1
J 0
(10885 3705);
DISPLAY 0.617021 (10885 3705);
PAINT WHITE (10885 3705);
FORCEPROP 1 LAST LOCATION C1T15
J 0
(10925 3725);
DISPLAY 0.617021 (10925 3725);
PAINT AQUA (10925 3725);
FORCEPROP 1 LAST VALUE 10UF
J 0
(10925 3675);
DISPLAY 0.617021 (10925 3675);
PAINT SKYBLUE (10925 3675);
FORCEPROP 2 LAST BOM_COST P1V538_BMC_STBY_VR
J 0
(10925 3775);
PAINT WHITE (10925 3775);
DISPLAY INVISIBLE (10925 3775);
FORCEPROP 2 LAST ROOM P1V538_BMC_STBY_VR
J 0
(10925 3825);
PAINT GREEN (10925 3825);
DISPLAY INVISIBLE (10925 3825);
FORCEPROP 1 LAST PATH I12
J 0
(10925 3775);
DISPLAY 0.978723 (10925 3775);
PAINT WHITE (10925 3775);
DISPLAY INVISIBLE (10925 3775);
FORCEPROP 2 LAST SEC_TYPE 0603
J 0
(10925 3825);
DISPLAY 1.659574 (10925 3825);
PAINT ORANGE (10925 3825);
DISPLAY INVISIBLE (10925 3825);
FORCEPROP 2 LAST SEC 1
J 0
(10925 3825);
DISPLAY 1.106383 (10925 3825);
PAINT MONO (10925 3825);
DISPLAY INVISIBLE (10925 3825);
FORCEPROP 2 LAST CDS_LIB mstr_discrete
J 0
(10875 3625);
PAINT ORANGE (10875 3625);
DISPLAY INVISIBLE (10875 3625);
FORCEPROP 2 LAST CDS_LOCATION C1T15
J 0
(10925 3725);
DISPLAY 0.617021 (10925 3725);
PAINT AQUA (10925 3725);
DISPLAY INVISIBLE (10925 3725);
FORCEADD GND..1
(10350 2900);
FORCEPROP 3 LASTPIN (10350 2950) SIG_NAME GND\g
J 0
(10360 2960);
DISPLAY 0.659574 (10360 2960);
PAINT MONO (10360 2960);
DISPLAY INVISIBLE (10360 2960);
FORCEPROP 2 LAST P1V5_STBY_IBMC_VR 
J 0
(10375 2975);
PAINT GREEN (10375 2975);
FORCEPROP 2 LAST P1V5_STBY_IBMC 
J 0
(10375 3025);
PAINT GREEN (10375 3025);
FORCEPROP 1 LAST HDL_POWER GND
J 0
(10350 3050);
DISPLAY 0.872340 (10350 3050);
PAINT GREEN (10350 3050);
DISPLAY INVISIBLE (10350 3050);
FORCEPROP 1 LAST BODY_TYPE PLUMBING
J 0
(10305 2857);
DISPLAY 0.340426 (10305 2857);
PAINT GREEN (10305 2857);
DISPLAY INVISIBLE (10305 2857);
FORCEPROP 2 LAST ROOM P1V538_BMC_STBY_VR
J 0
(10000 2975);
DISPLAY 0.872340 (10000 2975);
PAINT GREEN (10000 2975);
DISPLAY INVISIBLE (10000 2975);
FORCEPROP 1 LAST VOLTAGE 0.0V
J 0
(10305 2857);
DISPLAY 0.340426 (10305 2857);
PAINT SKYBLUE (10305 2857);
DISPLAY INVISIBLE (10305 2857);
FORCEPROP 1 LAST SIZE 1B
J 0
(10425 2850);
DISPLAY 0.872340 (10425 2850);
PAINT ORANGE (10425 2850);
DISPLAY INVISIBLE (10425 2850);
FORCEPROP 2 LAST CDS_LIB mstr_symbols
J 0
(10350 2900);
PAINT ORANGE (10350 2900);
DISPLAY INVISIBLE (10350 2900);
FORCEPROP 2 LAST BOM_COST P1V538_BMC_STBY_VR
J 0
(10375 3075);
PAINT WHITE (10375 3075);
DISPLAY INVISIBLE (10375 3075);
FORCEPROP 1 LAST PATH I16
J 0
(10425 2900);
DISPLAY 0.872340 (10425 2900);
PAINT AQUA (10425 2900);
DISPLAY INVISIBLE (10425 2900);
FORCEADD CAP..1
(5750 4150);
FORCEPROP 1 LAST PART_NUMBER E15431-002
J 0
(5800 4000);
DISPLAY 0.617021 (5800 4000);
PAINT BLUE (5800 4000);
FORCEPROP 1 LAST MATERIAL X6S
J 0
(5800 4050);
DISPLAY 0.617021 (5800 4050);
PAINT SKYBLUE (5800 4050);
FORCEPROP 1 LAST VOLTAGE 6.3V
J 0
(5800 4150);
DISPLAY 0.617021 (5800 4150);
PAINT SKYBLUE (5800 4150);
FORCEPROP 1 LAST TOLERANCE 20%
J 0
(5800 4100);
DISPLAY 0.617021 (5800 4100);
PAINT SKYBLUE (5800 4100);
FORCEPROP 1 LAST LOCATION C1T7
J 0
(5800 4250);
DISPLAY 0.617021 (5800 4250);
PAINT AQUA (5800 4250);
FORCEPROP 1 LAST VALUE 10UF
J 0
(5800 4200);
DISPLAY 0.617021 (5800 4200);
PAINT SKYBLUE (5800 4200);
FORCEPROP 1 LAST PACK_TYPE 0603
J 0
(5800 3950);
DISPLAY 0.617021 (5800 3950);
PAINT SKYBLUE (5800 3950);
FORCEPROP 1 LASTPIN (5750 4250) $PN 1
J 0
(5760 4230);
DISPLAY 0.617021 (5760 4230);
PAINT WHITE (5760 4230);
FORCEPROP 1 LASTPIN (5750 4050) $PN 2
J 0
(5760 4030);
DISPLAY 0.617021 (5760 4030);
PAINT WHITE (5760 4030);
FORCEPROP 2 LAST CDS_LIB mstr_discrete
J 0
(5750 4150);
PAINT ORANGE (5750 4150);
DISPLAY INVISIBLE (5750 4150);
FORCEPROP 2 LAST CDS_LOCATION C1T7
J 0
(5800 4250);
DISPLAY 0.617021 (5800 4250);
PAINT AQUA (5800 4250);
DISPLAY INVISIBLE (5800 4250);
FORCEPROP 2 LAST SEC 1
J 0
(5800 4350);
DISPLAY 1.106383 (5800 4350);
PAINT MONO (5800 4350);
DISPLAY INVISIBLE (5800 4350);
FORCEPROP 2 LAST SEC_TYPE 0603
J 0
(5800 4350);
DISPLAY 1.659574 (5800 4350);
PAINT ORANGE (5800 4350);
DISPLAY INVISIBLE (5800 4350);
FORCEPROP 1 LAST PATH I22
J 0
(5800 4300);
DISPLAY 0.978723 (5800 4300);
PAINT WHITE (5800 4300);
DISPLAY INVISIBLE (5800 4300);
FORCEPROP 2 LAST ROOM P1V538_BMC_STBY_VR
J 0
(5800 4300);
DISPLAY 0.723404 (5800 4300);
PAINT GREEN (5800 4300);
DISPLAY INVISIBLE (5800 4300);
FORCEPROP 2 LAST BOM_COST P1V538_BMC_STBY_VR
J 0
(5625 4300);
PAINT WHITE (5625 4300);
DISPLAY INVISIBLE (5625 4300);
FORCEADD CAP..1
R 2
(7050 3300);
FORCEPROP 1 LAST PACK_TYPE 0402LF
J 2
(6875 3250);
DISPLAY 0.617021 (6875 3250);
PAINT SKYBLUE (6875 3250);
FORCEPROP 1 LAST PART_NUMBER A36096-046
J 2
(7000 3150);
DISPLAY 0.617021 (7000 3150);
PAINT BLUE (7000 3150);
FORCEPROP 1 LAST VOLTAGE 50V
J 2
(7000 3300);
DISPLAY 0.617021 (7000 3300);
PAINT SKYBLUE (7000 3300);
FORCEPROP 1 LAST TOLERANCE 10%
J 2
(7000 3250);
DISPLAY 0.617021 (7000 3250);
PAINT SKYBLUE (7000 3250);
FORCEPROP 1 LAST LOCATION C9F6
J 2
(6875 3375);
DISPLAY 0.617021 (6875 3375);
PAINT AQUA (6875 3375);
FORCEPROP 1 LAST VALUE 1000PF
J 2
(6900 3325);
DISPLAY 0.617021 (6900 3325);
PAINT SKYBLUE (6900 3325);
FORCEPROP 1 LAST MATERIAL EMPTY
J 2
(7000 3200);
DISPLAY 0.617021 (7000 3200);
PAINT RED (7000 3200);
FORCEPROP 1 LASTPIN (7050 3200) $PN 2
J 2
(7040 3180);
DISPLAY 0.617021 (7040 3180);
PAINT WHITE (7040 3180);
FORCEPROP 1 LASTPIN (7050 3400) $PN 1
J 2
(7040 3380);
DISPLAY 0.617021 (7040 3380);
PAINT WHITE (7040 3380);
FORCEPROP 2 LAST BOM_COST P1V538_BMC_STBY_VR
J 0
(6985 3410);
DISPLAY 1.617021 (6985 3410);
PAINT WHITE (6985 3410);
DISPLAY INVISIBLE (6985 3410);
FORCEPROP 2 LAST ROOM P1V538_BMC_STBY_VR
J 2
(7000 3425);
DISPLAY 1.212766 (7000 3425);
PAINT GREEN (7000 3425);
DISPLAY INVISIBLE (7000 3425);
FORCEPROP 1 LAST PATH I30
J 2
(7000 3450);
DISPLAY 0.978723 (7000 3450);
PAINT WHITE (7000 3450);
DISPLAY INVISIBLE (7000 3450);
FORCEPROP 2 LAST $SEC 1
J 0
(7010 3510);
DISPLAY 1.617021 (7010 3510);
PAINT MONO (7010 3510);
DISPLAY INVISIBLE (7010 3510);
FORCEPROP 2 LAST CDS_LOCATION C9F6
J 2
(6875 3375);
DISPLAY 0.617021 (6875 3375);
PAINT AQUA (6875 3375);
DISPLAY INVISIBLE (6875 3375);
FORCEPROP 2 LAST CDS_LIB mstr_discrete
J 0
(7050 3300);
DISPLAY 1.617021 (7050 3300);
PAINT MONO (7050 3300);
DISPLAY INVISIBLE (7050 3300);
FORCEPROP 2 LAST CDS_SEC 1
J 0
(7010 3510);
DISPLAY 1.617021 (7010 3510);
PAINT MONO (7010 3510);
DISPLAY INVISIBLE (7010 3510);
FORCEADD OFFPAGE..1
(6375 3575);
FORCEPROP 2 LAST $XR0 239 
J 0
(6123 3575);
DISPLAY 0.638298 (6123 3575);
PAINT MONO (6123 3575);
FORCEPROP 1 LAST COMMENT_BODY TRUE
J 0
(6500 3475);
DISPLAY 1.170213 (6500 3475);
PAINT PEACH (6500 3475);
DISPLAY INVISIBLE (6500 3475);
FORCEPROP 1 LAST OFFPAGE TRUE
J 0
(6700 3450);
PAINT GREEN (6700 3450);
DISPLAY INVISIBLE (6700 3450);
FORCEPROP 2 LAST ROOM P1V538_BMC_STBY_VR
J 0
(5900 3650);
DISPLAY 1.340426 (5900 3650);
PAINT GREEN (5900 3650);
DISPLAY INVISIBLE (5900 3650);
FORCEPROP 2 LAST BOM_COST P1V538_BMC_STBY_VR
J 0
(6100 3625);
PAINT WHITE (6100 3625);
DISPLAY INVISIBLE (6100 3625);
FORCEPROP 2 LAST PATH I33
J 0
(6449 3649);
DISPLAY 1.021277 (6449 3649);
PAINT ORANGE (6449 3649);
DISPLAY INVISIBLE (6449 3649);
FORCEPROP 2 LAST CDS_LIB mstr_standard
J 0
(6375 3575);
DISPLAY 1.340426 (6375 3575);
PAINT ORANGE (6375 3575);
DISPLAY INVISIBLE (6375 3575);
FORCEADD P3V3_STBY..1
(9625 5000);
FORCEPROP 3 LASTPIN (9625 4950) SIG_NAME P3V3_STBY\g
J 0
(9635 4960);
DISPLAY 0.659574 (9635 4960);
PAINT MONO (9635 4960);
DISPLAY INVISIBLE (9635 4960);
FORCEPROP 1 LAST HDL_POWER P3V3_STBY
J 0
(9325 4875);
DISPLAY 0.872340 (9325 4875);
PAINT ORANGE (9325 4875);
DISPLAY INVISIBLE (9325 4875);
FORCEPROP 1 LAST BODY_TYPE PLUMBING
J 0
(9580 4957);
DISPLAY 0.340426 (9580 4957);
PAINT GREEN (9580 4957);
DISPLAY INVISIBLE (9580 4957);
FORCEPROP 1 LAST VOLTAGE 3.3V
J 0
(9580 4957);
DISPLAY 0.340426 (9580 4957);
PAINT SKYBLUE (9580 4957);
DISPLAY INVISIBLE (9580 4957);
FORCEPROP 1 LAST SIZE 1B
J 0
(9670 5022);
DISPLAY 0.340426 (9670 5022);
PAINT GREEN (9670 5022);
DISPLAY INVISIBLE (9670 5022);
FORCEPROP 1 LAST PATH I35
J 0
(9670 5002);
DISPLAY 0.340426 (9670 5002);
PAINT GREEN (9670 5002);
DISPLAY INVISIBLE (9670 5002);
FORCEPROP 2 LAST CDS_LIB mstr_symbols
J 0
(9625 5000);
PAINT ORANGE (9625 5000);
DISPLAY INVISIBLE (9625 5000);
FORCEADD GND..1
(7050 2875);
FORCEPROP 3 LASTPIN (7050 2925) SIG_NAME GND\g
J 0
(7060 2935);
DISPLAY 0.659574 (7060 2935);
PAINT MONO (7060 2935);
DISPLAY INVISIBLE (7060 2935);
FORCEPROP 2 LAST P1V5_STBY_IBMC_VR 
J 0
(7075 2950);
PAINT GREEN (7075 2950);
FORCEPROP 2 LAST P1V5_STBY_IBMC 
J 0
(7075 3000);
PAINT GREEN (7075 3000);
FORCEPROP 1 LAST HDL_POWER GND
J 0
(7050 3025);
DISPLAY 0.872340 (7050 3025);
PAINT GREEN (7050 3025);
DISPLAY INVISIBLE (7050 3025);
FORCEPROP 1 LAST BODY_TYPE PLUMBING
J 0
(7005 2832);
DISPLAY 0.340426 (7005 2832);
PAINT GREEN (7005 2832);
DISPLAY INVISIBLE (7005 2832);
FORCEPROP 2 LAST ROOM P1V538_BMC_STBY_VR
J 0
(6700 2950);
DISPLAY 0.872340 (6700 2950);
PAINT GREEN (6700 2950);
DISPLAY INVISIBLE (6700 2950);
FORCEPROP 1 LAST SIZE 1B
J 0
(7125 2825);
DISPLAY 0.872340 (7125 2825);
PAINT ORANGE (7125 2825);
DISPLAY INVISIBLE (7125 2825);
FORCEPROP 1 LAST VOLTAGE 0.0V
J 0
(7005 2832);
DISPLAY 0.340426 (7005 2832);
PAINT SKYBLUE (7005 2832);
DISPLAY INVISIBLE (7005 2832);
FORCEPROP 2 LAST BOM_COST P1V538_BMC_STBY_VR
J 0
(7075 3050);
PAINT WHITE (7075 3050);
DISPLAY INVISIBLE (7075 3050);
FORCEPROP 1 LAST PATH I38
J 0
(7125 2875);
DISPLAY 0.872340 (7125 2875);
PAINT AQUA (7125 2875);
DISPLAY INVISIBLE (7125 2875);
FORCEPROP 2 LAST CDS_LIB mstr_symbols
J 0
(7050 2875);
PAINT ORANGE (7050 2875);
DISPLAY INVISIBLE (7050 2875);
FORCEADD GND..1
(5750 3850);
FORCEPROP 3 LASTPIN (5750 3900) SIG_NAME GND\g
J 0
(5760 3910);
DISPLAY 0.659574 (5760 3910);
PAINT MONO (5760 3910);
DISPLAY INVISIBLE (5760 3910);
FORCEPROP 1 LAST PATH I39
J 0
(5825 3850);
DISPLAY 0.872340 (5825 3850);
PAINT AQUA (5825 3850);
DISPLAY INVISIBLE (5825 3850);
FORCEPROP 1 LAST HDL_POWER GND
J 0
(5750 4000);
DISPLAY 0.872340 (5750 4000);
PAINT GREEN (5750 4000);
DISPLAY INVISIBLE (5750 4000);
FORCEPROP 1 LAST BODY_TYPE PLUMBING
J 0
(5705 3807);
DISPLAY 0.340426 (5705 3807);
PAINT GREEN (5705 3807);
DISPLAY INVISIBLE (5705 3807);
FORCEPROP 1 LAST VOLTAGE 0.0V
J 0
(5705 3807);
DISPLAY 0.340426 (5705 3807);
PAINT SKYBLUE (5705 3807);
DISPLAY INVISIBLE (5705 3807);
FORCEPROP 1 LAST SIZE 1B
J 0
(5825 3800);
DISPLAY 0.872340 (5825 3800);
PAINT AQUA (5825 3800);
DISPLAY INVISIBLE (5825 3800);
FORCEPROP 2 LAST CDS_LIB mstr_symbols
J 0
(5750 3850);
PAINT ORANGE (5750 3850);
DISPLAY INVISIBLE (5750 3850);
FORCEADD CAP..1
(10375 4150);
FORCEPROP 1 LAST PACK_TYPE 0402LF
J 0
(10425 3950);
DISPLAY 0.617021 (10425 3950);
PAINT SKYBLUE (10425 3950);
FORCEPROP 1 LASTPIN (10375 4250) $PN 1
J 0
(10385 4230);
DISPLAY 0.617021 (10385 4230);
PAINT WHITE (10385 4230);
FORCEPROP 1 LAST LOCATION C9F10
J 0
(10250 4225);
DISPLAY 0.617021 (10250 4225);
PAINT AQUA (10250 4225);
FORCEPROP 1 LAST MATERIAL X7R
J 0
(10425 4050);
DISPLAY 0.617021 (10425 4050);
PAINT SKYBLUE (10425 4050);
FORCEPROP 1 LAST TOLERANCE 10%
J 0
(10425 4100);
DISPLAY 0.617021 (10425 4100);
PAINT SKYBLUE (10425 4100);
FORCEPROP 1 LAST VALUE 1000PF
J 0
(10425 4200);
DISPLAY 0.617021 (10425 4200);
PAINT SKYBLUE (10425 4200);
FORCEPROP 1 LASTPIN (10375 4050) $PN 2
J 0
(10385 4030);
DISPLAY 0.617021 (10385 4030);
PAINT WHITE (10385 4030);
FORCEPROP 1 LAST VOLTAGE 50V
J 0
(10425 4150);
DISPLAY 0.531915 (10425 4150);
PAINT SKYBLUE (10425 4150);
FORCEPROP 1 LAST PART_NUMBER A36096-046
J 0
(10425 4000);
DISPLAY 0.617021 (10425 4000);
PAINT BLUE (10425 4000);
FORCEPROP 2 LAST ROOM P1V538_BMC_STBY_VR
J 0
(10435 4290);
DISPLAY 1.617021 (10435 4290);
PAINT GREEN (10435 4290);
DISPLAY INVISIBLE (10435 4290);
FORCEPROP 2 LAST BOM_COST P1V538_BMC_STBY_VR
J 0
(10435 4290);
DISPLAY 1.617021 (10435 4290);
PAINT WHITE (10435 4290);
DISPLAY INVISIBLE (10435 4290);
FORCEPROP 1 LAST PATH I4
J 0
(10425 4300);
DISPLAY 0.978723 (10425 4300);
PAINT WHITE (10425 4300);
DISPLAY INVISIBLE (10425 4300);
FORCEPROP 2 LAST $SEC 1
J 0
(10435 4365);
DISPLAY 1.617021 (10435 4365);
PAINT MONO (10435 4365);
DISPLAY INVISIBLE (10435 4365);
FORCEPROP 2 LAST CDS_LOCATION C9F10
J 0
(10250 4225);
DISPLAY 0.617021 (10250 4225);
PAINT AQUA (10250 4225);
DISPLAY INVISIBLE (10250 4225);
FORCEPROP 2 LAST CDS_LIB mstr_discrete
J 0
(10375 4150);
DISPLAY 1.617021 (10375 4150);
PAINT MONO (10375 4150);
DISPLAY INVISIBLE (10375 4150);
FORCEPROP 2 LAST CDS_SEC 1
J 0
(10435 4365);
DISPLAY 1.617021 (10435 4365);
PAINT MONO (10435 4365);
DISPLAY INVISIBLE (10435 4365);
FORCEADD OFFPAGE..2
(11550 4275);
FORCEPROP 2 LAST $XR0 238 
J 0
(11739 4275);
DISPLAY 0.638298 (11739 4275);
PAINT MONO (11739 4275);
FORCEPROP 1 LAST COMMENT_BODY TRUE
J 0
(11505 4180);
DISPLAY 0.872340 (11505 4180);
PAINT GREEN (11505 4180);
DISPLAY INVISIBLE (11505 4180);
FORCEPROP 1 LAST OFFPAGE TRUE
J 0
(11875 4150);
DISPLAY 0.872340 (11875 4150);
PAINT GREEN (11875 4150);
DISPLAY INVISIBLE (11875 4150);
FORCEPROP 2 LAST PATH I42
J 0
(11725 4350);
DISPLAY 1.021277 (11725 4350);
PAINT ORANGE (11725 4350);
DISPLAY INVISIBLE (11725 4350);
FORCEPROP 2 LAST CDS_LIB mstr_standard
J 0
(11550 4275);
PAINT ORANGE (11550 4275);
DISPLAY INVISIBLE (11550 4275);
FORCEADD GND..1
(10375 3975);
FORCEPROP 3 LASTPIN (10375 4025) SIG_NAME GND\g
J 0
(10385 4035);
DISPLAY 0.659574 (10385 4035);
PAINT MONO (10385 4035);
DISPLAY INVISIBLE (10385 4035);
FORCEPROP 1 LAST HDL_POWER GND
J 0
(10375 4125);
DISPLAY 1.063830 (10375 4125);
PAINT GREEN (10375 4125);
DISPLAY INVISIBLE (10375 4125);
FORCEPROP 1 LAST BODY_TYPE PLUMBING
J 0
(10330 3932);
DISPLAY 0.340426 (10330 3932);
PAINT GREEN (10330 3932);
DISPLAY INVISIBLE (10330 3932);
FORCEPROP 2 LAST ROOM P1V538_BMC_STBY_VR
J 0
(9725 4050);
DISPLAY 1.212766 (9725 4050);
PAINT GREEN (9725 4050);
DISPLAY INVISIBLE (9725 4050);
FORCEPROP 1 LAST VOLTAGE 0.0V
J 0
(10330 3932);
DISPLAY 0.340426 (10330 3932);
PAINT SKYBLUE (10330 3932);
DISPLAY INVISIBLE (10330 3932);
FORCEPROP 1 LAST SIZE 1B
J 0
(10450 3925);
DISPLAY 1.063830 (10450 3925);
PAINT GREEN (10450 3925);
DISPLAY INVISIBLE (10450 3925);
FORCEPROP 2 LAST BOM_COST P1V538_BMC_STBY_VR
J 0
(10060 4065);
DISPLAY 1.617021 (10060 4065);
PAINT WHITE (10060 4065);
DISPLAY INVISIBLE (10060 4065);
FORCEPROP 1 LAST PATH I5
J 0
(10450 3975);
DISPLAY 0.872340 (10450 3975);
PAINT AQUA (10450 3975);
DISPLAY INVISIBLE (10450 3975);
FORCEPROP 2 LAST CDS_LIB mstr_symbols
J 0
(10375 3975);
DISPLAY 1.617021 (10375 3975);
PAINT MONO (10375 3975);
DISPLAY INVISIBLE (10375 3975);
FORCEADD RES..2
(9625 4525);
FORCEPROP 1 LASTPIN (9625 4425) $PN 2
J 0
(9630 4435);
DISPLAY 0.617021 (9630 4435);
PAINT WHITE (9630 4435);
FORCEPROP 1 LAST MATERIAL CHIP
J 0
(9665 4450);
DISPLAY 0.617021 (9665 4450);
PAINT SKYBLUE (9665 4450);
FORCEPROP 1 LAST PART_NUMBER G21796-016
J 0
(9665 4400);
DISPLAY 0.617021 (9665 4400);
PAINT BLUE (9665 4400);
FORCEPROP 1 LAST PACK_TYPE 0402
J 0
(9665 4350);
DISPLAY 0.617021 (9665 4350);
PAINT SKYBLUE (9665 4350);
FORCEPROP 2 LAST P1V5_STBY_IBMC_VR 
J 0
(9575 4675);
PAINT GREEN (9575 4675);
FORCEPROP 2 LAST P1V5_STBY_IBMC 
J 0
(9575 4725);
PAINT GREEN (9575 4725);
FORCEPROP 1 LASTPIN (9625 4625) $PN 1
J 0
(9630 4587);
DISPLAY 0.617021 (9630 4587);
PAINT WHITE (9630 4587);
FORCEPROP 1 LAST LOCATION R9F12
J 0
(9670 4650);
DISPLAY 0.617021 (9670 4650);
PAINT AQUA (9670 4650);
FORCEPROP 1 LAST VALUE 10.0K
J 0
(9670 4600);
DISPLAY 0.617021 (9670 4600);
PAINT SKYBLUE (9670 4600);
FORCEPROP 1 LAST TOLERANCE 1%
J 0
(9670 4550);
DISPLAY 0.617021 (9670 4550);
PAINT SKYBLUE (9670 4550);
FORCEPROP 1 LAST WATTAGE 1/16W
J 0
(9665 4500);
DISPLAY 0.617021 (9665 4500);
PAINT SKYBLUE (9665 4500);
FORCEPROP 2 LAST ROOM P1V538_BMC_STBY_VR
J 0
(9575 4625);
PAINT GREEN (9575 4625);
DISPLAY INVISIBLE (9575 4625);
FORCEPROP 2 LAST BOM_COST P1V538_BMC_STBY_VR
J 0
(9575 4775);
PAINT WHITE (9575 4775);
DISPLAY INVISIBLE (9575 4775);
FORCEPROP 1 LAST PATH I6
J 0
(9675 4700);
DISPLAY 0.978723 (9675 4700);
PAINT WHITE (9675 4700);
DISPLAY INVISIBLE (9675 4700);
FORCEPROP 2 LAST SEC 1
J 0
(9575 4775);
DISPLAY 1.106383 (9575 4775);
PAINT MONO (9575 4775);
DISPLAY INVISIBLE (9575 4775);
FORCEPROP 2 LAST SEC_TYPE 0402
J 0
(9575 4775);
DISPLAY 1.659574 (9575 4775);
PAINT ORANGE (9575 4775);
DISPLAY INVISIBLE (9575 4775);
FORCEPROP 2 LAST CDS_LIB mstr_discrete
J 0
(9625 4525);
PAINT ORANGE (9625 4525);
DISPLAY INVISIBLE (9625 4525);
FORCEPROP 2 LAST CDS_LOCATION R9F12
J 0
(9670 4650);
DISPLAY 0.617021 (9670 4650);
PAINT AQUA (9670 4650);
DISPLAY INVISIBLE (9670 4650);
FORCEADD GND..1
(9450 3350);
FORCEPROP 3 LASTPIN (9450 3400) SIG_NAME GND\g
J 0
(9460 3410);
DISPLAY 0.659574 (9460 3410);
PAINT MONO (9460 3410);
DISPLAY INVISIBLE (9460 3410);
FORCEPROP 2 LAST P1V5_STBY_IBMC 
J 0
(9475 3475);
PAINT GREEN (9475 3475);
FORCEPROP 2 LAST P1V5_STBY_IBMC_VR 
J 0
(9475 3425);
PAINT GREEN (9475 3425);
FORCEPROP 1 LAST HDL_POWER GND
J 0
(9450 3500);
DISPLAY 0.872340 (9450 3500);
PAINT GREEN (9450 3500);
DISPLAY INVISIBLE (9450 3500);
FORCEPROP 1 LAST BODY_TYPE PLUMBING
J 0
(9405 3307);
DISPLAY 0.340426 (9405 3307);
PAINT GREEN (9405 3307);
DISPLAY INVISIBLE (9405 3307);
FORCEPROP 2 LAST ROOM P1V26_BMC_STBY_VR
J 0
(9100 3425);
DISPLAY 0.872340 (9100 3425);
PAINT GREEN (9100 3425);
DISPLAY INVISIBLE (9100 3425);
FORCEPROP 1 LAST VOLTAGE 0.0V
J 0
(9405 3307);
DISPLAY 0.340426 (9405 3307);
PAINT SKYBLUE (9405 3307);
DISPLAY INVISIBLE (9405 3307);
FORCEPROP 2 LAST BOM_COST P1V26_BMC_STBY_VR
J 0
(9475 3525);
PAINT WHITE (9475 3525);
DISPLAY INVISIBLE (9475 3525);
FORCEPROP 1 LAST SIZE 1B
J 0
(9525 3300);
DISPLAY 0.872340 (9525 3300);
PAINT ORANGE (9525 3300);
DISPLAY INVISIBLE (9525 3300);
FORCEPROP 1 LAST PATH I62
J 0
(9525 3350);
DISPLAY 0.872340 (9525 3350);
PAINT AQUA (9525 3350);
DISPLAY INVISIBLE (9525 3350);
FORCEPROP 2 LAST CDS_LIB mstr_symbols
J 0
(9450 3350);
PAINT ORANGE (9450 3350);
DISPLAY INVISIBLE (9450 3350);
FORCEADD P3V3_STBY..1
(5750 4625);
FORCEPROP 3 LASTPIN (5750 4575) SIG_NAME P3V3_STBY\g
J 0
(5760 4585);
DISPLAY 0.659574 (5760 4585);
PAINT MONO (5760 4585);
DISPLAY INVISIBLE (5760 4585);
FORCEPROP 2 LAST CDS_LIB mstr_symbols
J 0
(5750 4625);
PAINT ORANGE (5750 4625);
DISPLAY INVISIBLE (5750 4625);
FORCEPROP 1 LAST PATH I67
J 0
(5795 4627);
DISPLAY 0.340426 (5795 4627);
PAINT GREEN (5795 4627);
DISPLAY INVISIBLE (5795 4627);
FORCEPROP 1 LAST SIZE 1B
J 0
(5795 4647);
DISPLAY 0.340426 (5795 4647);
PAINT GREEN (5795 4647);
DISPLAY INVISIBLE (5795 4647);
FORCEPROP 1 LAST VOLTAGE 3.3V
J 0
(5705 4582);
DISPLAY 0.340426 (5705 4582);
PAINT SKYBLUE (5705 4582);
DISPLAY INVISIBLE (5705 4582);
FORCEPROP 1 LAST BODY_TYPE PLUMBING
J 0
(5705 4582);
DISPLAY 0.340426 (5705 4582);
PAINT GREEN (5705 4582);
DISPLAY INVISIBLE (5705 4582);
FORCEPROP 1 LAST HDL_POWER P3V3_STBY
J 0
(5450 4500);
DISPLAY 0.872340 (5450 4500);
PAINT ORANGE (5450 4500);
DISPLAY INVISIBLE (5450 4500);
FORCEADD GND..1
(7475 3850);
FORCEPROP 3 LASTPIN (7475 3900) SIG_NAME GND\g
J 0
(7485 3910);
DISPLAY 0.659574 (7485 3910);
PAINT MONO (7485 3910);
DISPLAY INVISIBLE (7485 3910);
FORCEPROP 2 LAST P1V5_STBY_IBMC 
J 0
(7500 3975);
PAINT GREEN (7500 3975);
FORCEPROP 2 LAST P1V5_STBY_IBMC_VR 
J 0
(7500 3925);
PAINT GREEN (7500 3925);
FORCEPROP 1 LAST HDL_POWER GND
J 0
(7475 4000);
DISPLAY 0.872340 (7475 4000);
PAINT GREEN (7475 4000);
DISPLAY INVISIBLE (7475 4000);
FORCEPROP 1 LAST BODY_TYPE PLUMBING
J 0
(7430 3807);
DISPLAY 0.340426 (7430 3807);
PAINT GREEN (7430 3807);
DISPLAY INVISIBLE (7430 3807);
FORCEPROP 2 LAST ROOM P1V26_BMC_STBY_VR
J 0
(7125 3925);
DISPLAY 0.872340 (7125 3925);
PAINT GREEN (7125 3925);
DISPLAY INVISIBLE (7125 3925);
FORCEPROP 1 LAST VOLTAGE 0.0V
J 0
(7430 3807);
DISPLAY 0.340426 (7430 3807);
PAINT SKYBLUE (7430 3807);
DISPLAY INVISIBLE (7430 3807);
FORCEPROP 1 LAST SIZE 1B
J 0
(7550 3800);
DISPLAY 0.872340 (7550 3800);
PAINT ORANGE (7550 3800);
DISPLAY INVISIBLE (7550 3800);
FORCEPROP 2 LAST BOM_COST P1V26_BMC_STBY_VR
J 0
(7500 4025);
PAINT WHITE (7500 4025);
DISPLAY INVISIBLE (7500 4025);
FORCEPROP 1 LAST PATH I69
J 0
(7550 3850);
DISPLAY 0.872340 (7550 3850);
PAINT AQUA (7550 3850);
DISPLAY INVISIBLE (7550 3850);
FORCEPROP 2 LAST CDS_LIB mstr_symbols
J 0
(7475 3850);
PAINT ORANGE (7475 3850);
DISPLAY INVISIBLE (7475 3850);
FORCEADD CAP..1
(11725 3575);
FORCEPROP 1 LAST PACK_TYPE 0805LF
J 0
(11775 3375);
DISPLAY 0.617021 (11775 3375);
PAINT SKYBLUE (11775 3375);
FORCEPROP 1 LAST PART_NUMBER C95333-002
J 0
(11775 3425);
DISPLAY 0.617021 (11775 3425);
PAINT BLUE (11775 3425);
FORCEPROP 1 LAST VALUE 22UF
J 0
(11775 3625);
DISPLAY 0.617021 (11775 3625);
PAINT SKYBLUE (11775 3625);
FORCEPROP 1 LAST LOCATION C9F13
J 0
(11775 3675);
DISPLAY 0.617021 (11775 3675);
PAINT AQUA (11775 3675);
FORCEPROP 1 LAST TOLERANCE 20%
J 0
(11775 3525);
DISPLAY 0.617021 (11775 3525);
PAINT SKYBLUE (11775 3525);
FORCEPROP 1 LAST VOLTAGE 4V
J 0
(11775 3575);
DISPLAY 0.617021 (11775 3575);
PAINT SKYBLUE (11775 3575);
FORCEPROP 1 LASTPIN (11725 3675) $PN 1
J 0
(11735 3655);
DISPLAY 0.617021 (11735 3655);
PAINT WHITE (11735 3655);
FORCEPROP 1 LAST MATERIAL X6S
J 0
(11775 3475);
DISPLAY 0.617021 (11775 3475);
PAINT SKYBLUE (11775 3475);
FORCEPROP 1 LASTPIN (11725 3475) $PN 2
J 0
(11735 3455);
DISPLAY 0.617021 (11735 3455);
PAINT WHITE (11735 3455);
FORCEPROP 2 LAST CDS_LOCATION C9F13
J 0
(11775 3675);
DISPLAY 0.617021 (11775 3675);
PAINT AQUA (11775 3675);
DISPLAY INVISIBLE (11775 3675);
FORCEPROP 2 LAST CDS_LIB mstr_discrete
J 0
(11725 3575);
PAINT ORANGE (11725 3575);
DISPLAY INVISIBLE (11725 3575);
FORCEPROP 2 LAST SEC 1
J 0
(11775 3775);
DISPLAY 1.106383 (11775 3775);
PAINT MONO (11775 3775);
DISPLAY INVISIBLE (11775 3775);
FORCEPROP 2 LAST SEC_TYPE 0805LF
J 0
(11775 3775);
DISPLAY 1.659574 (11775 3775);
PAINT ORANGE (11775 3775);
DISPLAY INVISIBLE (11775 3775);
FORCEPROP 1 LAST PATH I7
J 0
(11775 3725);
DISPLAY 0.978723 (11775 3725);
PAINT WHITE (11775 3725);
DISPLAY INVISIBLE (11775 3725);
FORCEPROP 2 LAST ROOM P1V538_BMC_STBY_VR
J 0
(11775 3775);
PAINT GREEN (11775 3775);
DISPLAY INVISIBLE (11775 3775);
FORCEPROP 2 LAST BOM_COST P1V538_BMC_STBY_VR
J 0
(11775 3725);
PAINT WHITE (11775 3725);
DISPLAY INVISIBLE (11775 3725);
FORCEADD RT9059..1
(8850 3775);
FORCEPROP 2 LASTPIN (9350 3475) $PN 11
J 0
(9360 3485);
DISPLAY 0.617021 (9360 3485);
PAINT ORANGE (9360 3485);
FORCEPROP 2 LASTPIN (9350 3575) $PN 4
J 0
(9360 3585);
DISPLAY 0.617021 (9360 3585);
PAINT ORANGE (9360 3585);
FORCEPROP 1 LAST MATERIAL IC
J 0
(8400 4175);
DISPLAY 0.617021 (8400 4175);
PAINT SKYBLUE (8400 4175);
FORCEPROP 1 LAST LOCATION EU9F2
J 0
(8400 4225);
DISPLAY 0.617021 (8400 4225);
PAINT AQUA (8400 4225);
FORCEPROP 2 LASTPIN (8350 3575) $PN 6
J 2
(8340 3585);
DISPLAY 0.617021 (8340 3585);
PAINT ORANGE (8340 3585);
FORCEPROP 2 LASTPIN (8350 3975) $PN 10
J 2
(8340 3985);
DISPLAY 0.617021 (8340 3985);
PAINT ORANGE (8340 3985);
FORCEPROP 2 LASTPIN (8350 3725) $PN 7
J 2
(8340 3735);
DISPLAY 0.617021 (8340 3735);
PAINT ORANGE (8340 3735);
FORCEPROP 2 LASTPIN (8350 3775) $PN 8
J 2
(8340 3785);
DISPLAY 0.617021 (8340 3785);
PAINT ORANGE (8340 3785);
FORCEPROP 2 LASTPIN (8350 3825) $PN 9
J 2
(8340 3835);
DISPLAY 0.617021 (8340 3835);
PAINT ORANGE (8340 3835);
FORCEPROP 2 LASTPIN (9350 3825) $PN 3
J 0
(9360 3835);
DISPLAY 0.617021 (9360 3835);
PAINT ORANGE (9360 3835);
FORCEPROP 2 LASTPIN (9350 3775) $PN 2
J 0
(9360 3785);
DISPLAY 0.617021 (9360 3785);
PAINT ORANGE (9360 3785);
FORCEPROP 2 LASTPIN (9350 3975) $PN 5
J 0
(9360 3985);
DISPLAY 0.617021 (9360 3985);
PAINT ORANGE (9360 3985);
FORCEPROP 2 LASTPIN (9350 3725) $PN 1
J 0
(9360 3735);
DISPLAY 0.617021 (9360 3735);
PAINT ORANGE (9360 3735);
FORCEPROP 1 LAST PART_NUMBER H65765-001
J 0
(8400 3375);
DISPLAY 0.617021 (8400 3375);
PAINT BLUE (8400 3375);
FORCEPROP 1 LAST PACK_TYPE DFN
J 0
(8400 4275);
PAINT SKYBLUE (8400 4275);
DISPLAY INVISIBLE (8400 4275);
FORCEPROP 1 LAST PATH I70
J 0
(8900 4175);
PAINT GREEN (8900 4175);
DISPLAY INVISIBLE (8900 4175);
FORCEPROP 2 LAST SEC 1
J 0
(8400 4275);
DISPLAY 0.680851 (8400 4275);
PAINT MONO (8400 4275);
DISPLAY INVISIBLE (8400 4275);
FORCEPROP 2 LAST SEC_TYPE DFN
J 0
(8400 4275);
DISPLAY 1.021277 (8400 4275);
PAINT ORANGE (8400 4275);
DISPLAY INVISIBLE (8400 4275);
FORCEPROP 2 LAST CDS_LOCATION EU9F2
J 0
(8400 4225);
DISPLAY 0.617021 (8400 4225);
PAINT AQUA (8400 4225);
DISPLAY INVISIBLE (8400 4225);
FORCEPROP 2 LAST CDS_LIB mstr_vreg
J 0
(8850 3775);
PAINT ORANGE (8850 3775);
DISPLAY INVISIBLE (8850 3775);
FORCEADD CAP_A..1
(7475 4125);
FORCEPROP 1 LAST VOLTAGE 16V
J 0
(7525 4125);
DISPLAY 0.617021 (7525 4125);
PAINT SKYBLUE (7525 4125);
FORCEPROP 1 LAST VALUE 0.1UF
J 0
(7525 4175);
DISPLAY 0.617021 (7525 4175);
PAINT SKYBLUE (7525 4175);
FORCEPROP 1 LAST TOLERANCE 10%
J 0
(7525 4075);
DISPLAY 0.617021 (7525 4075);
PAINT SKYBLUE (7525 4075);
FORCEPROP 1 LAST MATERIAL X7R
J 0
(7525 4025);
DISPLAY 0.617021 (7525 4025);
PAINT SKYBLUE (7525 4025);
FORCEPROP 1 LAST LOCATION C9F5
J 0
(7525 4225);
DISPLAY 0.617021 (7525 4225);
PAINT AQUA (7525 4225);
FORCEPROP 1 LAST PACK_TYPE 0402V
J 0
(7525 3925);
DISPLAY 0.617021 (7525 3925);
PAINT SKYBLUE (7525 3925);
FORCEPROP 1 LASTPIN (7475 4025) $PN 2
J 0
(7485 4005);
DISPLAY 0.617021 (7485 4005);
PAINT ORANGE (7485 4005);
FORCEPROP 1 LASTPIN (7475 4225) $PN 1
J 0
(7485 4205);
DISPLAY 0.617021 (7485 4205);
PAINT ORANGE (7485 4205);
FORCEPROP 1 LAST PART_NUMBER A36096-030
J 0
(7525 3975);
DISPLAY 0.617021 (7525 3975);
PAINT BLUE (7525 3975);
FORCEPROP 1 LAST PATH I71
J 0
(7525 4275);
DISPLAY 0.978723 (7525 4275);
PAINT WHITE (7525 4275);
DISPLAY INVISIBLE (7525 4275);
FORCEPROP 2 LAST SEC 1
J 0
(7525 4325);
PAINT MONO (7525 4325);
DISPLAY INVISIBLE (7525 4325);
FORCEPROP 2 LAST SEC_TYPE 0402V
J 0
(7525 4325);
DISPLAY 1.021277 (7525 4325);
PAINT ORANGE (7525 4325);
DISPLAY INVISIBLE (7525 4325);
FORCEPROP 2 LAST CDS_SEC 1
J 0
(7525 4275);
PAINT ORANGE (7525 4275);
DISPLAY INVISIBLE (7525 4275);
FORCEPROP 2 LAST CDS_LIB dev_discrete
J 0
(7475 4125);
PAINT ORANGE (7475 4125);
DISPLAY INVISIBLE (7475 4125);
FORCEPROP 2 LAST CDS_LOCATION C9F5
J 0
(7525 4225);
DISPLAY 0.617021 (7525 4225);
PAINT AQUA (7525 4225);
DISPLAY INVISIBLE (7525 4225);
FORCEADD RES..1
(10700 4275);
FORCEPROP 1 LASTPIN (10600 4275) $PN 1
J 0
(10612 4287);
DISPLAY 0.617021 (10612 4287);
PAINT ORANGE (10612 4287);
FORCEPROP 1 LASTPIN (10800 4275) $PN 2
J 0
(10762 4287);
DISPLAY 0.617021 (10762 4287);
PAINT ORANGE (10762 4287);
FORCEPROP 1 LAST LOCATION R1T9
J 0
(10650 4325);
DISPLAY 0.617021 (10650 4325);
PAINT AQUA (10650 4325);
FORCEPROP 1 LAST PART_NUMBER G21796-250
J 0
(10650 4375);
DISPLAY 0.617021 (10650 4375);
PAINT BLUE (10650 4375);
FORCEPROP 1 LAST PACK_TYPE 0402
J 0
(10950 4125);
DISPLAY 0.617021 (10950 4125);
PAINT SKYBLUE (10950 4125);
FORCEPROP 1 LAST VALUE 22.1
J 2
(10675 4175);
DISPLAY 0.617021 (10675 4175);
PAINT SKYBLUE (10675 4175);
FORCEPROP 1 LAST WATTAGE 1/16W
J 2
(10675 4125);
DISPLAY 0.617021 (10675 4125);
PAINT SKYBLUE (10675 4125);
FORCEPROP 1 LAST TOLERANCE 1.0%
J 0
(10700 4175);
DISPLAY 0.617021 (10700 4175);
PAINT SKYBLUE (10700 4175);
FORCEPROP 1 LAST MATERIAL CHIP
J 0
(10700 4125);
DISPLAY 0.617021 (10700 4125);
PAINT SKYBLUE (10700 4125);
FORCEPROP 0 LAST ROOM P1V538_BMC_STBY_VR
J 0
(10650 4475);
DISPLAY 1.021277 (10650 4475);
PAINT ORANGE (10650 4475);
DISPLAY INVISIBLE (10650 4475);
FORCEPROP 1 LAST PATH I72
J 0
(10650 4425);
DISPLAY 0.978723 (10650 4425);
PAINT WHITE (10650 4425);
DISPLAY INVISIBLE (10650 4425);
FORCEPROP 2 LAST SEC 1
J 0
(10650 4475);
DISPLAY 0.680851 (10650 4475);
PAINT MONO (10650 4475);
DISPLAY INVISIBLE (10650 4475);
FORCEPROP 2 LAST SEC_TYPE 0402
J 0
(10650 4475);
DISPLAY 1.021277 (10650 4475);
PAINT ORANGE (10650 4475);
DISPLAY INVISIBLE (10650 4475);
FORCEPROP 2 LAST CDS_LOCATION R1T9
J 0
(10650 4325);
DISPLAY 0.617021 (10650 4325);
PAINT AQUA (10650 4325);
DISPLAY INVISIBLE (10650 4325);
FORCEPROP 2 LAST CDS_LIB mstr_discrete
J 0
(10700 4275);
PAINT MONO (10700 4275);
DISPLAY INVISIBLE (10700 4275);
FORCEADD RT9059..1
(8425 1700);
FORCEPROP 1 LAST LOCATION EU25F2
J 0
(7975 2150);
DISPLAY 0.617021 (7975 2150);
PAINT AQUA (7975 2150);
FORCEPROP 1 LAST PART_NUMBER H65765-001
J 0
(7975 1300);
DISPLAY 0.617021 (7975 1300);
PAINT BLUE (7975 1300);
FORCEPROP 1 LAST MATERIAL IC
J 0
(7975 2100);
DISPLAY 0.617021 (7975 2100);
PAINT SKYBLUE (7975 2100);
FORCEPROP 2 LAST CDS_LIB mstr_vreg
J 0
(8425 1700);
PAINT MONO (8425 1700);
DISPLAY INVISIBLE (8425 1700);
FORCEPROP 1 LAST PATH I73
J 0
(8475 2100);
PAINT GREEN (8475 2100);
DISPLAY INVISIBLE (8475 2100);
FORCEPROP 1 LAST PACK_TYPE DFN
J 0
(7975 2200);
PAINT SKYBLUE (7975 2200);
DISPLAY INVISIBLE (7975 2200);
FORCEADD GND..1
(7250 1800);
FORCEPROP 3 LASTPIN (7250 1850) SIG_NAME GND\g
J 0
(7260 1860);
DISPLAY 0.659574 (7260 1860);
PAINT MONO (7260 1860);
DISPLAY INVISIBLE (7260 1860);
FORCEPROP 2 LAST P1V5_STBY_IBMC 
J 0
(7275 1925);
PAINT GREEN (7275 1925);
FORCEPROP 2 LAST P1V5_STBY_IBMC_VR 
J 0
(7275 1875);
PAINT GREEN (7275 1875);
FORCEPROP 2 LAST ROOM P1V26_BMC_STBY_VR
J 0
(6900 1875);
DISPLAY 0.872340 (6900 1875);
PAINT GREEN (6900 1875);
DISPLAY INVISIBLE (6900 1875);
FORCEPROP 1 LAST VOLTAGE 0.0V
J 0
(7205 1757);
DISPLAY 0.340426 (7205 1757);
PAINT SKYBLUE (7205 1757);
DISPLAY INVISIBLE (7205 1757);
FORCEPROP 1 LAST SIZE 1B
J 0
(7325 1750);
DISPLAY 0.872340 (7325 1750);
PAINT ORANGE (7325 1750);
DISPLAY INVISIBLE (7325 1750);
FORCEPROP 2 LAST BOM_COST P1V26_BMC_STBY_VR
J 0
(7275 1975);
PAINT WHITE (7275 1975);
DISPLAY INVISIBLE (7275 1975);
FORCEPROP 1 LAST PATH I74
J 0
(7325 1800);
DISPLAY 0.872340 (7325 1800);
PAINT AQUA (7325 1800);
DISPLAY INVISIBLE (7325 1800);
FORCEPROP 2 LAST CDS_LIB mstr_symbols
J 0
(7250 1800);
PAINT MONO (7250 1800);
DISPLAY INVISIBLE (7250 1800);
FORCEPROP 1 LAST BODY_TYPE PLUMBING
J 0
(7205 1757);
DISPLAY 0.340426 (7205 1757);
PAINT GREEN (7205 1757);
DISPLAY INVISIBLE (7205 1757);
FORCEPROP 1 LAST HDL_POWER GND
J 0
(7250 1950);
DISPLAY 0.872340 (7250 1950);
PAINT GREEN (7250 1950);
DISPLAY INVISIBLE (7250 1950);
FORCEADD P3V3_STBY..1
(5575 2550);
FORCEPROP 3 LASTPIN (5575 2500) SIG_NAME P3V3_STBY\g
J 0
(5585 2510);
DISPLAY 0.659574 (5585 2510);
PAINT MONO (5585 2510);
DISPLAY INVISIBLE (5585 2510);
FORCEPROP 1 LAST VOLTAGE 3.3V
J 0
(5530 2507);
DISPLAY 0.340426 (5530 2507);
PAINT SKYBLUE (5530 2507);
DISPLAY INVISIBLE (5530 2507);
FORCEPROP 1 LAST SIZE 1B
J 0
(5620 2572);
DISPLAY 0.340426 (5620 2572);
PAINT GREEN (5620 2572);
DISPLAY INVISIBLE (5620 2572);
FORCEPROP 1 LAST PATH I75
J 0
(5620 2552);
DISPLAY 0.340426 (5620 2552);
PAINT GREEN (5620 2552);
DISPLAY INVISIBLE (5620 2552);
FORCEPROP 2 LAST CDS_LIB mstr_symbols
J 0
(5575 2550);
PAINT MONO (5575 2550);
DISPLAY INVISIBLE (5575 2550);
FORCEPROP 1 LAST BODY_TYPE PLUMBING
J 0
(5530 2507);
DISPLAY 0.340426 (5530 2507);
PAINT GREEN (5530 2507);
DISPLAY INVISIBLE (5530 2507);
FORCEPROP 1 LAST HDL_POWER P3V3_STBY
J 0
(5275 2425);
DISPLAY 0.872340 (5275 2425);
PAINT ORANGE (5275 2425);
DISPLAY INVISIBLE (5275 2425);
FORCEADD OFFPAGE..2
(11125 2200);
FORCEPROP 2 LAST $XR0 239 
J 0
(11314 2200);
DISPLAY 0.638298 (11314 2200);
PAINT MONO (11314 2200);
FORCEPROP 1 LAST COMMENT_BODY TRUE
J 0
(11080 2105);
DISPLAY 0.872340 (11080 2105);
PAINT GREEN (11080 2105);
DISPLAY INVISIBLE (11080 2105);
FORCEPROP 1 LAST OFFPAGE TRUE
J 0
(11450 2075);
DISPLAY 0.872340 (11450 2075);
PAINT GREEN (11450 2075);
DISPLAY INVISIBLE (11450 2075);
FORCEPROP 2 LAST CDS_LIB mstr_standard
J 0
(11125 2200);
PAINT MONO (11125 2200);
DISPLAY INVISIBLE (11125 2200);
FORCEPROP 2 LAST PATH I76
J 0
(11300 2275);
DISPLAY 1.021277 (11300 2275);
PAINT ORANGE (11300 2275);
DISPLAY INVISIBLE (11300 2275);
FORCEADD RES..1
(10275 2200);
FORCEPROP 1 LAST PART_NUMBER G21796-250
J 0
(10225 2300);
DISPLAY 0.617021 (10225 2300);
PAINT BLUE (10225 2300);
FORCEPROP 1 LAST PACK_TYPE 0402
J 0
(10500 2075);
DISPLAY 0.617021 (10500 2075);
PAINT SKYBLUE (10500 2075);
FORCEPROP 1 LAST WATTAGE 1/16W
J 2
(10350 2075);
DISPLAY 0.617021 (10350 2075);
PAINT SKYBLUE (10350 2075);
FORCEPROP 1 LAST VALUE 22.1
J 2
(10350 2125);
DISPLAY 0.617021 (10350 2125);
PAINT SKYBLUE (10350 2125);
FORCEPROP 1 LASTPIN (10375 2200) $PN 2
J 0
(10337 2212);
DISPLAY 0.787234 (10337 2212);
PAINT ORANGE (10337 2212);
FORCEPROP 1 LASTPIN (10175 2200) $PN 1
J 0
(10187 2212);
DISPLAY 0.787234 (10187 2212);
PAINT ORANGE (10187 2212);
FORCEPROP 1 LAST MATERIAL CHIP
J 0
(10375 2075);
DISPLAY 0.617021 (10375 2075);
PAINT SKYBLUE (10375 2075);
FORCEPROP 1 LAST TOLERANCE 1.0%
J 0
(10375 2125);
DISPLAY 0.617021 (10375 2125);
PAINT SKYBLUE (10375 2125);
FORCEPROP 1 LAST LOCATION R1W9
J 0
(10225 2250);
DISPLAY 0.617021 (10225 2250);
PAINT AQUA (10225 2250);
FORCEPROP 2 LAST CDS_LIB mstr_discrete
J 0
(10275 2200);
PAINT MONO (10275 2200);
DISPLAY INVISIBLE (10275 2200);
FORCEPROP 1 LAST PATH I77
J 0
(10225 2350);
DISPLAY 0.978723 (10225 2350);
PAINT WHITE (10225 2350);
DISPLAY INVISIBLE (10225 2350);
FORCEPROP 0 LAST ROOM P1V538_BMC_STBY_VR
J 0
(10225 2400);
DISPLAY 1.021277 (10225 2400);
PAINT ORANGE (10225 2400);
DISPLAY INVISIBLE (10225 2400);
FORCEPROP 0 LAST SEC 1
J 0
(10225 2350);
DISPLAY 0.680851 (10225 2350);
PAINT MONO (10225 2350);
DISPLAY INVISIBLE (10225 2350);
FORCEPROP 2 LAST SEC_TYPE 0402
J 0
(10225 2400);
DISPLAY 1.021277 (10225 2400);
PAINT ORANGE (10225 2400);
DISPLAY INVISIBLE (10225 2400);
FORCEADD P3V3_STBY..1
(9200 2700);
FORCEPROP 3 LASTPIN (9200 2650) SIG_NAME P3V3_STBY\g
J 0
(9210 2660);
DISPLAY 0.659574 (9210 2660);
PAINT MONO (9210 2660);
DISPLAY INVISIBLE (9210 2660);
FORCEPROP 1 LAST HDL_POWER P3V3_STBY
J 0
(8900 2575);
DISPLAY 0.872340 (8900 2575);
PAINT ORANGE (8900 2575);
DISPLAY INVISIBLE (8900 2575);
FORCEPROP 1 LAST BODY_TYPE PLUMBING
J 0
(9155 2657);
DISPLAY 0.340426 (9155 2657);
PAINT GREEN (9155 2657);
DISPLAY INVISIBLE (9155 2657);
FORCEPROP 2 LAST CDS_LIB mstr_symbols
J 0
(9200 2700);
PAINT MONO (9200 2700);
DISPLAY INVISIBLE (9200 2700);
FORCEPROP 1 LAST PATH I78
J 0
(9245 2702);
DISPLAY 0.340426 (9245 2702);
PAINT GREEN (9245 2702);
DISPLAY INVISIBLE (9245 2702);
FORCEPROP 1 LAST VOLTAGE 3.3V
J 0
(9155 2657);
DISPLAY 0.340426 (9155 2657);
PAINT SKYBLUE (9155 2657);
DISPLAY INVISIBLE (9155 2657);
FORCEPROP 1 LAST SIZE 1B
J 0
(9245 2722);
DISPLAY 0.340426 (9245 2722);
PAINT GREEN (9245 2722);
DISPLAY INVISIBLE (9245 2722);
FORCEADD RES..2
(9200 2450);
FORCEPROP 1 LAST PACK_TYPE 0402
J 0
(9240 2275);
DISPLAY 0.617021 (9240 2275);
PAINT SKYBLUE (9240 2275);
FORCEPROP 1 LASTPIN (9200 2350) $PN 2
J 0
(9205 2360);
DISPLAY 0.787234 (9205 2360);
PAINT ORANGE (9205 2360);
FORCEPROP 1 LAST PART_NUMBER G21796-016
J 0
(9240 2325);
DISPLAY 0.617021 (9240 2325);
PAINT BLUE (9240 2325);
FORCEPROP 1 LAST VALUE 10.0K
J 0
(9245 2525);
DISPLAY 0.617021 (9245 2525);
PAINT SKYBLUE (9245 2525);
FORCEPROP 2 LAST P1V5_STBY_IBMC 
J 0
(9150 2650);
PAINT GREEN (9150 2650);
FORCEPROP 2 LAST P1V5_STBY_IBMC_VR 
J 0
(9150 2600);
PAINT GREEN (9150 2600);
FORCEPROP 1 LAST LOCATION R9W12
J 0
(9245 2575);
DISPLAY 0.617021 (9245 2575);
PAINT AQUA (9245 2575);
FORCEPROP 1 LAST TOLERANCE 1%
J 0
(9245 2475);
DISPLAY 0.617021 (9245 2475);
PAINT SKYBLUE (9245 2475);
FORCEPROP 1 LAST MATERIAL CHIP
J 0
(9240 2375);
DISPLAY 0.617021 (9240 2375);
PAINT SKYBLUE (9240 2375);
FORCEPROP 1 LAST WATTAGE 1/16W
J 0
(9240 2425);
DISPLAY 0.617021 (9240 2425);
PAINT SKYBLUE (9240 2425);
FORCEPROP 1 LASTPIN (9200 2550) $PN 1
J 0
(9205 2512);
DISPLAY 0.787234 (9205 2512);
PAINT ORANGE (9205 2512);
FORCEPROP 2 LAST CDS_LIB mstr_discrete
J 0
(9200 2450);
PAINT MONO (9200 2450);
DISPLAY INVISIBLE (9200 2450);
FORCEPROP 1 LAST PATH I79
J 0
(9250 2625);
DISPLAY 0.978723 (9250 2625);
PAINT WHITE (9250 2625);
DISPLAY INVISIBLE (9250 2625);
FORCEPROP 2 LAST BOM_COST P1V538_BMC_STBY_VR
J 0
(9150 2700);
PAINT WHITE (9150 2700);
DISPLAY INVISIBLE (9150 2700);
FORCEPROP 2 LAST ROOM P1V538_BMC_STBY_VR
J 0
(9150 2550);
PAINT GREEN (9150 2550);
DISPLAY INVISIBLE (9150 2550);
FORCEPROP 0 LAST SEC 1
J 0
(9150 2700);
DISPLAY 0.680851 (9150 2700);
PAINT MONO (9150 2700);
DISPLAY INVISIBLE (9150 2700);
FORCEPROP 2 LAST SEC_TYPE 0402
J 0
(9150 2700);
DISPLAY 1.021277 (9150 2700);
PAINT ORANGE (9150 2700);
DISPLAY INVISIBLE (9150 2700);
FORCEADD CAP..1
(11300 1500);
FORCEPROP 1 LASTPIN (11300 1400) $PN 2
J 0
(11310 1380);
DISPLAY 0.787234 (11310 1380);
PAINT ORANGE (11310 1380);
FORCEPROP 1 LAST PART_NUMBER C95333-002
J 0
(11350 1350);
DISPLAY 0.617021 (11350 1350);
PAINT BLUE (11350 1350);
FORCEPROP 1 LAST MATERIAL X6S
J 0
(11350 1400);
DISPLAY 0.617021 (11350 1400);
PAINT SKYBLUE (11350 1400);
FORCEPROP 1 LAST TOLERANCE 20%
J 0
(11350 1450);
DISPLAY 0.617021 (11350 1450);
PAINT SKYBLUE (11350 1450);
FORCEPROP 1 LAST PACK_TYPE 0805LF
J 0
(11350 1300);
DISPLAY 0.617021 (11350 1300);
PAINT SKYBLUE (11350 1300);
FORCEPROP 1 LAST LOCATION C9W13
J 0
(11350 1600);
DISPLAY 0.617021 (11350 1600);
PAINT AQUA (11350 1600);
FORCEPROP 1 LAST VALUE 22UF
J 0
(11350 1550);
DISPLAY 0.617021 (11350 1550);
PAINT SKYBLUE (11350 1550);
FORCEPROP 1 LASTPIN (11300 1600) $PN 1
J 0
(11310 1580);
DISPLAY 0.787234 (11310 1580);
PAINT ORANGE (11310 1580);
FORCEPROP 1 LAST VOLTAGE 4V
J 0
(11350 1500);
DISPLAY 0.617021 (11350 1500);
PAINT SKYBLUE (11350 1500);
FORCEPROP 0 LAST SEC 1
J 0
(11350 1650);
DISPLAY 0.680851 (11350 1650);
PAINT MONO (11350 1650);
DISPLAY INVISIBLE (11350 1650);
FORCEPROP 2 LAST SEC_TYPE 0805LF
J 0
(11350 1700);
DISPLAY 1.021277 (11350 1700);
PAINT ORANGE (11350 1700);
DISPLAY INVISIBLE (11350 1700);
FORCEPROP 2 LAST CDS_LIB mstr_discrete
J 0
(11300 1500);
PAINT MONO (11300 1500);
DISPLAY INVISIBLE (11300 1500);
FORCEPROP 1 LAST PATH I81
J 0
(11350 1650);
DISPLAY 0.978723 (11350 1650);
PAINT WHITE (11350 1650);
DISPLAY INVISIBLE (11350 1650);
FORCEPROP 2 LAST ROOM P1V538_BMC_STBY_VR
J 0
(11350 1700);
PAINT GREEN (11350 1700);
DISPLAY INVISIBLE (11350 1700);
FORCEPROP 2 LAST BOM_COST P1V538_BMC_STBY_VR
J 0
(11350 1650);
PAINT WHITE (11350 1650);
DISPLAY INVISIBLE (11350 1650);
FORCEADD GND..1
(11300 1175);
FORCEPROP 3 LASTPIN (11300 1225) SIG_NAME GND\g
J 0
(11310 1235);
DISPLAY 0.659574 (11310 1235);
PAINT MONO (11310 1235);
DISPLAY INVISIBLE (11310 1235);
FORCEPROP 2 LAST P1V5_STBY_IBMC 
J 0
(11325 1300);
PAINT GREEN (11325 1300);
FORCEPROP 2 LAST P1V5_STBY_IBMC_VR 
J 0
(11325 1250);
PAINT GREEN (11325 1250);
FORCEPROP 1 LAST HDL_POWER GND
J 0
(11300 1325);
DISPLAY 0.872340 (11300 1325);
PAINT GREEN (11300 1325);
DISPLAY INVISIBLE (11300 1325);
FORCEPROP 1 LAST BODY_TYPE PLUMBING
J 0
(11255 1132);
DISPLAY 0.340426 (11255 1132);
PAINT GREEN (11255 1132);
DISPLAY INVISIBLE (11255 1132);
FORCEPROP 2 LAST CDS_LIB mstr_symbols
J 0
(11300 1175);
PAINT MONO (11300 1175);
DISPLAY INVISIBLE (11300 1175);
FORCEPROP 1 LAST PATH I82
J 0
(11375 1175);
DISPLAY 0.872340 (11375 1175);
PAINT AQUA (11375 1175);
DISPLAY INVISIBLE (11375 1175);
FORCEPROP 2 LAST BOM_COST P1V538_BMC_STBY_VR
J 0
(11325 1350);
PAINT WHITE (11325 1350);
DISPLAY INVISIBLE (11325 1350);
FORCEPROP 1 LAST SIZE 1B
J 0
(11375 1125);
DISPLAY 0.872340 (11375 1125);
PAINT ORANGE (11375 1125);
DISPLAY INVISIBLE (11375 1125);
FORCEPROP 1 LAST VOLTAGE 0.0V
J 0
(11255 1132);
DISPLAY 0.340426 (11255 1132);
PAINT SKYBLUE (11255 1132);
DISPLAY INVISIBLE (11255 1132);
FORCEPROP 2 LAST ROOM P1V538_BMC_STBY_VR
J 0
(10950 1250);
DISPLAY 0.872340 (10950 1250);
PAINT GREEN (10950 1250);
DISPLAY INVISIBLE (10950 1250);
FORCEADD CAP..1
(10450 1500);
FORCEPROP 1 LAST PART_NUMBER E15431-002
J 0
(10500 1350);
DISPLAY 0.617021 (10500 1350);
PAINT BLUE (10500 1350);
FORCEPROP 1 LAST PACK_TYPE 0603
J 0
(10500 1300);
DISPLAY 0.617021 (10500 1300);
PAINT SKYBLUE (10500 1300);
FORCEPROP 1 LAST TOLERANCE 20%
J 0
(10500 1450);
DISPLAY 0.617021 (10500 1450);
PAINT SKYBLUE (10500 1450);
FORCEPROP 1 LAST VOLTAGE 6.3V
J 0
(10500 1500);
DISPLAY 0.617021 (10500 1500);
PAINT SKYBLUE (10500 1500);
FORCEPROP 1 LASTPIN (10450 1400) $PN 2
J 0
(10460 1380);
DISPLAY 0.787234 (10460 1380);
PAINT ORANGE (10460 1380);
FORCEPROP 1 LAST LOCATION C1W15
J 0
(10500 1600);
DISPLAY 0.617021 (10500 1600);
PAINT AQUA (10500 1600);
FORCEPROP 1 LAST VALUE 10UF
J 0
(10500 1550);
DISPLAY 0.617021 (10500 1550);
PAINT SKYBLUE (10500 1550);
FORCEPROP 1 LASTPIN (10450 1600) $PN 1
J 0
(10460 1580);
DISPLAY 0.787234 (10460 1580);
PAINT ORANGE (10460 1580);
FORCEPROP 1 LAST MATERIAL X6S
J 0
(10500 1400);
DISPLAY 0.617021 (10500 1400);
PAINT SKYBLUE (10500 1400);
FORCEPROP 2 LAST BOM_COST P1V538_BMC_STBY_VR
J 0
(10500 1650);
PAINT WHITE (10500 1650);
DISPLAY INVISIBLE (10500 1650);
FORCEPROP 2 LAST ROOM P1V538_BMC_STBY_VR
J 0
(10500 1700);
PAINT GREEN (10500 1700);
DISPLAY INVISIBLE (10500 1700);
FORCEPROP 1 LAST PATH I83
J 0
(10500 1650);
DISPLAY 0.978723 (10500 1650);
PAINT WHITE (10500 1650);
DISPLAY INVISIBLE (10500 1650);
FORCEPROP 2 LAST CDS_LIB mstr_discrete
J 0
(10450 1500);
PAINT MONO (10450 1500);
DISPLAY INVISIBLE (10450 1500);
FORCEPROP 2 LAST SEC_TYPE 0603
J 0
(10500 1700);
DISPLAY 1.021277 (10500 1700);
PAINT ORANGE (10500 1700);
DISPLAY INVISIBLE (10500 1700);
FORCEPROP 0 LAST SEC 1
J 0
(10500 1650);
DISPLAY 0.680851 (10500 1650);
PAINT MONO (10500 1650);
DISPLAY INVISIBLE (10500 1650);
FORCEADD CAP..1
(9950 2075);
FORCEPROP 1 LAST VOLTAGE 50V
J 0
(10000 1850);
DISPLAY 0.531915 (10000 1850);
PAINT SKYBLUE (10000 1850);
FORCEPROP 1 LAST PART_NUMBER A36096-046
J 0
(10000 1950);
DISPLAY 0.617021 (10000 1950);
PAINT BLUE (10000 1950);
FORCEPROP 1 LAST TOLERANCE 10%
J 0
(10000 2050);
DISPLAY 0.617021 (10000 2050);
PAINT SKYBLUE (10000 2050);
FORCEPROP 1 LAST VALUE 1000PF
J 0
(10000 2100);
DISPLAY 0.617021 (10000 2100);
PAINT SKYBLUE (10000 2100);
FORCEPROP 1 LASTPIN (9950 1975) $PN 2
J 0
(9960 1955);
DISPLAY 0.787234 (9960 1955);
PAINT ORANGE (9960 1955);
FORCEPROP 1 LASTPIN (9950 2175) $PN 1
J 0
(9960 2155);
DISPLAY 0.787234 (9960 2155);
PAINT ORANGE (9960 2155);
FORCEPROP 1 LAST PACK_TYPE 0402LF
J 0
(10000 1900);
DISPLAY 0.617021 (10000 1900);
PAINT SKYBLUE (10000 1900);
FORCEPROP 1 LAST MATERIAL X7R
J 0
(10000 2000);
DISPLAY 0.617021 (10000 2000);
PAINT SKYBLUE (10000 2000);
FORCEPROP 1 LAST LOCATION C9W10
J 0
(10000 2150);
DISPLAY 0.617021 (10000 2150);
PAINT AQUA (10000 2150);
FORCEPROP 2 LAST CDS_LIB mstr_discrete
J 0
(9950 2075);
PAINT MONO (9950 2075);
DISPLAY INVISIBLE (9950 2075);
FORCEPROP 1 LAST PATH I84
J 0
(10000 2225);
DISPLAY 0.978723 (10000 2225);
PAINT WHITE (10000 2225);
DISPLAY INVISIBLE (10000 2225);
FORCEPROP 2 LAST BOM_COST P1V538_BMC_STBY_VR
J 0
(10010 2215);
DISPLAY 1.617021 (10010 2215);
PAINT WHITE (10010 2215);
DISPLAY INVISIBLE (10010 2215);
FORCEPROP 2 LAST ROOM P1V538_BMC_STBY_VR
J 0
(10010 2215);
DISPLAY 1.617021 (10010 2215);
PAINT GREEN (10010 2215);
DISPLAY INVISIBLE (10010 2215);
FORCEPROP 0 LAST SEC 1
J 0
(9825 2200);
DISPLAY 0.680851 (9825 2200);
PAINT MONO (9825 2200);
DISPLAY INVISIBLE (9825 2200);
FORCEPROP 2 LAST SEC_TYPE 0402LF
J 0
(10000 2275);
DISPLAY 1.021277 (10000 2275);
PAINT ORANGE (10000 2275);
DISPLAY INVISIBLE (10000 2275);
FORCEADD GND..1
(9950 1900);
FORCEPROP 3 LASTPIN (9950 1950) SIG_NAME GND\g
J 0
(9960 1960);
DISPLAY 0.659574 (9960 1960);
PAINT MONO (9960 1960);
DISPLAY INVISIBLE (9960 1960);
FORCEPROP 1 LAST HDL_POWER GND
J 0
(9950 2050);
DISPLAY 1.063830 (9950 2050);
PAINT GREEN (9950 2050);
DISPLAY INVISIBLE (9950 2050);
FORCEPROP 1 LAST BODY_TYPE PLUMBING
J 0
(9905 1857);
DISPLAY 0.340426 (9905 1857);
PAINT GREEN (9905 1857);
DISPLAY INVISIBLE (9905 1857);
FORCEPROP 2 LAST CDS_LIB mstr_symbols
J 0
(9950 1900);
PAINT MONO (9950 1900);
DISPLAY INVISIBLE (9950 1900);
FORCEPROP 1 LAST PATH I85
J 0
(10025 1900);
DISPLAY 0.872340 (10025 1900);
PAINT AQUA (10025 1900);
DISPLAY INVISIBLE (10025 1900);
FORCEPROP 2 LAST BOM_COST P1V538_BMC_STBY_VR
J 0
(9635 1990);
DISPLAY 1.617021 (9635 1990);
PAINT WHITE (9635 1990);
DISPLAY INVISIBLE (9635 1990);
FORCEPROP 1 LAST SIZE 1B
J 0
(10025 1850);
DISPLAY 1.063830 (10025 1850);
PAINT GREEN (10025 1850);
DISPLAY INVISIBLE (10025 1850);
FORCEPROP 1 LAST VOLTAGE 0.0V
J 0
(9905 1857);
DISPLAY 0.340426 (9905 1857);
PAINT SKYBLUE (9905 1857);
DISPLAY INVISIBLE (9905 1857);
FORCEPROP 2 LAST ROOM P1V538_BMC_STBY_VR
J 0
(9300 1975);
DISPLAY 1.212766 (9300 1975);
PAINT GREEN (9300 1975);
DISPLAY INVISIBLE (9300 1975);
FORCEADD GND..1
(9925 625);
FORCEPROP 3 LASTPIN (9925 675) SIG_NAME GND\g
J 0
(9935 685);
DISPLAY 0.659574 (9935 685);
PAINT MONO (9935 685);
DISPLAY INVISIBLE (9935 685);
FORCEPROP 2 LAST P1V5_STBY_IBMC_VR 
J 0
(9950 700);
PAINT GREEN (9950 700);
FORCEPROP 2 LAST P1V5_STBY_IBMC 
J 0
(9950 750);
PAINT GREEN (9950 750);
FORCEPROP 1 LAST HDL_POWER GND
J 0
(9925 775);
DISPLAY 0.872340 (9925 775);
PAINT GREEN (9925 775);
DISPLAY INVISIBLE (9925 775);
FORCEPROP 1 LAST BODY_TYPE PLUMBING
J 0
(9880 582);
DISPLAY 0.340426 (9880 582);
PAINT GREEN (9880 582);
DISPLAY INVISIBLE (9880 582);
FORCEPROP 2 LAST CDS_LIB mstr_symbols
J 0
(9925 625);
PAINT MONO (9925 625);
DISPLAY INVISIBLE (9925 625);
FORCEPROP 1 LAST PATH I88
J 0
(10000 625);
DISPLAY 0.872340 (10000 625);
PAINT AQUA (10000 625);
DISPLAY INVISIBLE (10000 625);
FORCEPROP 2 LAST ROOM P1V538_BMC_STBY_VR
J 0
(9575 700);
DISPLAY 0.872340 (9575 700);
PAINT GREEN (9575 700);
DISPLAY INVISIBLE (9575 700);
FORCEPROP 1 LAST VOLTAGE 0.0V
J 0
(9880 582);
DISPLAY 0.340426 (9880 582);
PAINT SKYBLUE (9880 582);
DISPLAY INVISIBLE (9880 582);
FORCEPROP 1 LAST SIZE 1B
J 0
(10000 575);
DISPLAY 0.872340 (10000 575);
PAINT ORANGE (10000 575);
DISPLAY INVISIBLE (10000 575);
FORCEPROP 2 LAST BOM_COST P1V538_BMC_STBY_VR
J 0
(9950 800);
PAINT WHITE (9950 800);
DISPLAY INVISIBLE (9950 800);
FORCEADD GND..1
(9025 1275);
FORCEPROP 3 LASTPIN (9025 1325) SIG_NAME GND\g
J 0
(9035 1335);
DISPLAY 0.659574 (9035 1335);
PAINT MONO (9035 1335);
DISPLAY INVISIBLE (9035 1335);
FORCEPROP 2 LAST P1V5_STBY_IBMC_VR 
J 0
(9050 1350);
PAINT GREEN (9050 1350);
FORCEPROP 2 LAST P1V5_STBY_IBMC 
J 0
(9050 1400);
PAINT GREEN (9050 1400);
FORCEPROP 1 LAST HDL_POWER GND
J 0
(9025 1425);
DISPLAY 0.872340 (9025 1425);
PAINT GREEN (9025 1425);
DISPLAY INVISIBLE (9025 1425);
FORCEPROP 1 LAST BODY_TYPE PLUMBING
J 0
(8980 1232);
DISPLAY 0.340426 (8980 1232);
PAINT GREEN (8980 1232);
DISPLAY INVISIBLE (8980 1232);
FORCEPROP 2 LAST CDS_LIB mstr_symbols
J 0
(9025 1275);
PAINT MONO (9025 1275);
DISPLAY INVISIBLE (9025 1275);
FORCEPROP 1 LAST PATH I89
J 0
(9100 1275);
DISPLAY 0.872340 (9100 1275);
PAINT AQUA (9100 1275);
DISPLAY INVISIBLE (9100 1275);
FORCEPROP 1 LAST SIZE 1B
J 0
(9100 1225);
DISPLAY 0.872340 (9100 1225);
PAINT ORANGE (9100 1225);
DISPLAY INVISIBLE (9100 1225);
FORCEPROP 2 LAST BOM_COST P1V26_BMC_STBY_VR
J 0
(9050 1450);
PAINT WHITE (9050 1450);
DISPLAY INVISIBLE (9050 1450);
FORCEPROP 1 LAST VOLTAGE 0.0V
J 0
(8980 1232);
DISPLAY 0.340426 (8980 1232);
PAINT SKYBLUE (8980 1232);
DISPLAY INVISIBLE (8980 1232);
FORCEPROP 2 LAST ROOM P1V26_BMC_STBY_VR
J 0
(8675 1350);
DISPLAY 0.872340 (8675 1350);
PAINT GREEN (8675 1350);
DISPLAY INVISIBLE (8675 1350);
FORCEADD GND..1
(11725 3225);
FORCEPROP 3 LASTPIN (11725 3275) SIG_NAME GND\g
J 0
(11735 3285);
DISPLAY 0.659574 (11735 3285);
PAINT MONO (11735 3285);
DISPLAY INVISIBLE (11735 3285);
FORCEPROP 2 LAST P1V5_STBY_IBMC 
J 0
(11750 3350);
PAINT GREEN (11750 3350);
FORCEPROP 2 LAST P1V5_STBY_IBMC_VR 
J 0
(11750 3300);
PAINT GREEN (11750 3300);
FORCEPROP 2 LAST CDS_LIB mstr_symbols
J 0
(11725 3225);
PAINT ORANGE (11725 3225);
DISPLAY INVISIBLE (11725 3225);
FORCEPROP 1 LAST PATH I9
J 0
(11800 3225);
DISPLAY 0.872340 (11800 3225);
PAINT AQUA (11800 3225);
DISPLAY INVISIBLE (11800 3225);
FORCEPROP 2 LAST BOM_COST P1V538_BMC_STBY_VR
J 0
(11750 3400);
PAINT WHITE (11750 3400);
DISPLAY INVISIBLE (11750 3400);
FORCEPROP 1 LAST SIZE 1B
J 0
(11800 3175);
DISPLAY 0.872340 (11800 3175);
PAINT ORANGE (11800 3175);
DISPLAY INVISIBLE (11800 3175);
FORCEPROP 1 LAST VOLTAGE 0.0V
J 0
(11680 3182);
DISPLAY 0.340426 (11680 3182);
PAINT SKYBLUE (11680 3182);
DISPLAY INVISIBLE (11680 3182);
FORCEPROP 2 LAST ROOM P1V538_BMC_STBY_VR
J 0
(11375 3300);
DISPLAY 0.872340 (11375 3300);
PAINT GREEN (11375 3300);
DISPLAY INVISIBLE (11375 3300);
FORCEPROP 1 LAST BODY_TYPE PLUMBING
J 0
(11680 3182);
DISPLAY 0.340426 (11680 3182);
PAINT GREEN (11680 3182);
DISPLAY INVISIBLE (11680 3182);
FORCEPROP 1 LAST HDL_POWER GND
J 0
(11725 3375);
DISPLAY 0.872340 (11725 3375);
PAINT GREEN (11725 3375);
DISPLAY INVISIBLE (11725 3375);
FORCEADD CAP_A..1
(7250 2075);
FORCEPROP 1 LAST PART_NUMBER A36096-030
J 0
(7300 1925);
DISPLAY 0.617021 (7300 1925);
PAINT BLUE (7300 1925);
FORCEPROP 1 LAST PACK_TYPE 0402V
J 0
(7300 1875);
DISPLAY 0.617021 (7300 1875);
PAINT SKYBLUE (7300 1875);
FORCEPROP 1 LAST MATERIAL X7R
J 0
(7300 1975);
DISPLAY 0.617021 (7300 1975);
PAINT SKYBLUE (7300 1975);
FORCEPROP 1 LAST TOLERANCE 10%
J 0
(7300 2025);
DISPLAY 0.617021 (7300 2025);
PAINT SKYBLUE (7300 2025);
FORCEPROP 1 LASTPIN (7250 1975) $PN 2
J 0
(7260 1955);
DISPLAY 0.787234 (7260 1955);
PAINT ORANGE (7260 1955);
FORCEPROP 1 LASTPIN (7250 2175) $PN 1
J 0
(7260 2155);
DISPLAY 0.787234 (7260 2155);
PAINT ORANGE (7260 2155);
FORCEPROP 1 LAST VALUE 0.1UF
J 0
(7300 2125);
DISPLAY 0.617021 (7300 2125);
PAINT SKYBLUE (7300 2125);
FORCEPROP 1 LAST LOCATION C9W5
J 0
(7300 2175);
DISPLAY 0.617021 (7300 2175);
PAINT AQUA (7300 2175);
FORCEPROP 1 LAST VOLTAGE 16V
J 0
(7300 2075);
DISPLAY 0.617021 (7300 2075);
PAINT SKYBLUE (7300 2075);
FORCEPROP 2 LAST SEC_TYPE 0402V
J 0
(7300 2275);
DISPLAY 1.021277 (7300 2275);
PAINT ORANGE (7300 2275);
DISPLAY INVISIBLE (7300 2275);
FORCEPROP 0 LAST SEC 1
J 0
(7300 2225);
DISPLAY 0.680851 (7300 2225);
PAINT MONO (7300 2225);
DISPLAY INVISIBLE (7300 2225);
FORCEPROP 1 LAST PATH I90
J 0
(7300 2225);
DISPLAY 0.978723 (7300 2225);
PAINT WHITE (7300 2225);
DISPLAY INVISIBLE (7300 2225);
FORCEPROP 2 LAST CDS_LIB dev_discrete
J 0
(7250 2075);
PAINT MONO (7250 2075);
DISPLAY INVISIBLE (7250 2075);
FORCEADD CAP..1
R 2
(6625 1225);
FORCEPROP 1 LAST VALUE 1000PF
J 2
(6475 1250);
DISPLAY 0.617021 (6475 1250);
PAINT SKYBLUE (6475 1250);
FORCEPROP 1 LAST PART_NUMBER A36096-046
J 2
(6575 1075);
DISPLAY 0.617021 (6575 1075);
PAINT BLUE (6575 1075);
FORCEPROP 1 LAST LOCATION C9W6
J 2
(6450 1300);
DISPLAY 0.617021 (6450 1300);
PAINT AQUA (6450 1300);
FORCEPROP 1 LAST VOLTAGE 50V
J 2
(6575 1225);
DISPLAY 0.617021 (6575 1225);
PAINT SKYBLUE (6575 1225);
FORCEPROP 1 LAST TOLERANCE 10%
J 2
(6575 1175);
DISPLAY 0.617021 (6575 1175);
PAINT SKYBLUE (6575 1175);
FORCEPROP 1 LAST MATERIAL EMPTY
J 2
(6575 1125);
DISPLAY 0.617021 (6575 1125);
PAINT RED (6575 1125);
FORCEPROP 1 LAST PACK_TYPE 0402LF
J 2
(6450 1175);
DISPLAY 0.617021 (6450 1175);
PAINT SKYBLUE (6450 1175);
FORCEPROP 1 LASTPIN (6625 1325) $PN 1
J 2
(6615 1305);
DISPLAY 0.787234 (6615 1305);
PAINT ORANGE (6615 1305);
FORCEPROP 1 LASTPIN (6625 1125) $PN 2
J 2
(6615 1105);
DISPLAY 0.787234 (6615 1105);
PAINT ORANGE (6615 1105);
FORCEPROP 2 LAST CDS_LIB mstr_discrete
J 0
(6625 1225);
PAINT MONO (6625 1225);
DISPLAY INVISIBLE (6625 1225);
FORCEPROP 1 LAST PATH I91
J 2
(6575 1375);
DISPLAY 0.978723 (6575 1375);
PAINT WHITE (6575 1375);
DISPLAY INVISIBLE (6575 1375);
FORCEPROP 2 LAST ROOM P1V538_BMC_STBY_VR
J 2
(6575 1350);
DISPLAY 1.212766 (6575 1350);
PAINT GREEN (6575 1350);
DISPLAY INVISIBLE (6575 1350);
FORCEPROP 2 LAST BOM_COST P1V538_BMC_STBY_VR
J 0
(6560 1335);
DISPLAY 1.617021 (6560 1335);
PAINT WHITE (6560 1335);
DISPLAY INVISIBLE (6560 1335);
FORCEPROP 0 LAST SEC 1
J 0
(6450 1350);
DISPLAY 0.680851 (6450 1350);
PAINT MONO (6450 1350);
DISPLAY INVISIBLE (6450 1350);
FORCEPROP 2 LAST SEC_TYPE 0402LF
J 0
(6575 1425);
DISPLAY 1.021277 (6575 1425);
PAINT ORANGE (6575 1425);
DISPLAY INVISIBLE (6575 1425);
FORCEADD CAP..1
(5575 2075);
FORCEPROP 1 LASTPIN (5575 1975) $PN 2
J 0
(5585 1955);
DISPLAY 0.787234 (5585 1955);
PAINT ORANGE (5585 1955);
FORCEPROP 1 LASTPIN (5575 2175) $PN 1
J 0
(5585 2155);
DISPLAY 0.787234 (5585 2155);
PAINT ORANGE (5585 2155);
FORCEPROP 1 LAST PACK_TYPE 0603
J 0
(5625 1875);
DISPLAY 0.617021 (5625 1875);
PAINT SKYBLUE (5625 1875);
FORCEPROP 1 LAST TOLERANCE 20%
J 0
(5625 2025);
DISPLAY 0.617021 (5625 2025);
PAINT SKYBLUE (5625 2025);
FORCEPROP 1 LAST MATERIAL X6S
J 0
(5625 1975);
DISPLAY 0.617021 (5625 1975);
PAINT SKYBLUE (5625 1975);
FORCEPROP 1 LAST PART_NUMBER E15431-002
J 0
(5625 1925);
DISPLAY 0.617021 (5625 1925);
PAINT BLUE (5625 1925);
FORCEPROP 1 LAST LOCATION C1W7
J 0
(5625 2175);
DISPLAY 0.617021 (5625 2175);
PAINT AQUA (5625 2175);
FORCEPROP 1 LAST VALUE 10UF
J 0
(5625 2125);
DISPLAY 0.617021 (5625 2125);
PAINT SKYBLUE (5625 2125);
FORCEPROP 1 LAST VOLTAGE 6.3V
J 0
(5625 2075);
DISPLAY 0.617021 (5625 2075);
PAINT SKYBLUE (5625 2075);
FORCEPROP 2 LAST SEC_TYPE 0603
J 0
(5625 2275);
DISPLAY 1.021277 (5625 2275);
PAINT ORANGE (5625 2275);
DISPLAY INVISIBLE (5625 2275);
FORCEPROP 0 LAST SEC 1
J 0
(5625 2225);
DISPLAY 0.680851 (5625 2225);
PAINT MONO (5625 2225);
DISPLAY INVISIBLE (5625 2225);
FORCEPROP 2 LAST BOM_COST P1V538_BMC_STBY_VR
J 0
(5450 2225);
PAINT WHITE (5450 2225);
DISPLAY INVISIBLE (5450 2225);
FORCEPROP 2 LAST ROOM P1V538_BMC_STBY_VR
J 0
(5625 2225);
DISPLAY 0.723404 (5625 2225);
PAINT GREEN (5625 2225);
DISPLAY INVISIBLE (5625 2225);
FORCEPROP 1 LAST PATH I92
J 0
(5625 2225);
DISPLAY 0.978723 (5625 2225);
PAINT WHITE (5625 2225);
DISPLAY INVISIBLE (5625 2225);
FORCEPROP 2 LAST CDS_LIB mstr_discrete
J 0
(5575 2075);
PAINT MONO (5575 2075);
DISPLAY INVISIBLE (5575 2075);
FORCEADD GND..1
(5575 1775);
FORCEPROP 3 LASTPIN (5575 1825) SIG_NAME GND\g
J 0
(5585 1835);
DISPLAY 0.659574 (5585 1835);
PAINT MONO (5585 1835);
DISPLAY INVISIBLE (5585 1835);
FORCEPROP 1 LAST VOLTAGE 0.0V
J 0
(5530 1732);
DISPLAY 0.340426 (5530 1732);
PAINT SKYBLUE (5530 1732);
DISPLAY INVISIBLE (5530 1732);
FORCEPROP 1 LAST SIZE 1B
J 0
(5650 1725);
DISPLAY 0.872340 (5650 1725);
PAINT AQUA (5650 1725);
DISPLAY INVISIBLE (5650 1725);
FORCEPROP 1 LAST PATH I93
J 0
(5650 1775);
DISPLAY 0.872340 (5650 1775);
PAINT AQUA (5650 1775);
DISPLAY INVISIBLE (5650 1775);
FORCEPROP 2 LAST CDS_LIB mstr_symbols
J 0
(5575 1775);
PAINT MONO (5575 1775);
DISPLAY INVISIBLE (5575 1775);
FORCEPROP 1 LAST BODY_TYPE PLUMBING
J 0
(5530 1732);
DISPLAY 0.340426 (5530 1732);
PAINT GREEN (5530 1732);
DISPLAY INVISIBLE (5530 1732);
FORCEPROP 1 LAST HDL_POWER GND
J 0
(5575 1925);
DISPLAY 0.872340 (5575 1925);
PAINT GREEN (5575 1925);
DISPLAY INVISIBLE (5575 1925);
FORCEADD OFFPAGE..1
(5950 1500);
FORCEPROP 2 LAST $XR5 237 
J 0
(5548 1464);
DISPLAY 0.638298 (5548 1464);
PAINT MONO (5548 1464);
FORCEPROP 2 LAST $XR4 196 
J 0
(5668 1464);
DISPLAY 0.638298 (5668 1464);
PAINT MONO (5668 1464);
FORCEPROP 2 LAST $XR3 191 
J 0
(5308 1500);
DISPLAY 0.638298 (5308 1500);
PAINT MONO (5308 1500);
FORCEPROP 2 LAST $XR2 189 
J 0
(5428 1500);
DISPLAY 0.638298 (5428 1500);
PAINT MONO (5428 1500);
FORCEPROP 2 LAST $XR1 101 
J 0
(5548 1500);
DISPLAY 0.638298 (5548 1500);
PAINT MONO (5548 1500);
FORCEPROP 2 LAST $XR0 240 
J 0
(5668 1500);
DISPLAY 0.638298 (5668 1500);
PAINT MONO (5668 1500);
FORCEPROP 1 LAST COMMENT_BODY TRUE
J 0
(6075 1400);
DISPLAY 1.170213 (6075 1400);
PAINT PEACH (6075 1400);
DISPLAY INVISIBLE (6075 1400);
FORCEPROP 1 LAST OFFPAGE TRUE
J 0
(6275 1375);
PAINT GREEN (6275 1375);
DISPLAY INVISIBLE (6275 1375);
FORCEPROP 2 LAST CDS_LIB mstr_standard
J 0
(5950 1500);
PAINT MONO (5950 1500);
DISPLAY INVISIBLE (5950 1500);
FORCEPROP 2 LAST PATH I94
J 0
(6000 1575);
DISPLAY 1.021277 (6000 1575);
PAINT ORANGE (6000 1575);
DISPLAY INVISIBLE (6000 1575);
FORCEPROP 2 LAST BOM_COST P1V538_BMC_STBY_VR
J 0
(5675 1550);
PAINT WHITE (5675 1550);
DISPLAY INVISIBLE (5675 1550);
FORCEPROP 2 LAST ROOM P1V538_BMC_STBY_VR
J 0
(5475 1575);
DISPLAY 1.340426 (5475 1575);
PAINT GREEN (5475 1575);
DISPLAY INVISIBLE (5475 1575);
FORCEADD GND..1
(6625 800);
FORCEPROP 3 LASTPIN (6625 850) SIG_NAME GND\g
J 0
(6635 860);
DISPLAY 0.659574 (6635 860);
PAINT MONO (6635 860);
DISPLAY INVISIBLE (6635 860);
FORCEPROP 2 LAST P1V5_STBY_IBMC 
J 0
(6650 925);
PAINT GREEN (6650 925);
FORCEPROP 2 LAST P1V5_STBY_IBMC_VR 
J 0
(6650 875);
PAINT GREEN (6650 875);
FORCEPROP 1 LAST HDL_POWER GND
J 0
(6625 950);
DISPLAY 0.872340 (6625 950);
PAINT GREEN (6625 950);
DISPLAY INVISIBLE (6625 950);
FORCEPROP 1 LAST BODY_TYPE PLUMBING
J 0
(6580 757);
DISPLAY 0.340426 (6580 757);
PAINT GREEN (6580 757);
DISPLAY INVISIBLE (6580 757);
FORCEPROP 2 LAST CDS_LIB mstr_symbols
J 0
(6625 800);
PAINT MONO (6625 800);
DISPLAY INVISIBLE (6625 800);
FORCEPROP 1 LAST PATH I95
J 0
(6700 800);
DISPLAY 0.872340 (6700 800);
PAINT AQUA (6700 800);
DISPLAY INVISIBLE (6700 800);
FORCEPROP 2 LAST BOM_COST P1V538_BMC_STBY_VR
J 0
(6650 975);
PAINT WHITE (6650 975);
DISPLAY INVISIBLE (6650 975);
FORCEPROP 1 LAST VOLTAGE 0.0V
J 0
(6580 757);
DISPLAY 0.340426 (6580 757);
PAINT SKYBLUE (6580 757);
DISPLAY INVISIBLE (6580 757);
FORCEPROP 1 LAST SIZE 1B
J 0
(6700 750);
DISPLAY 0.872340 (6700 750);
PAINT ORANGE (6700 750);
DISPLAY INVISIBLE (6700 750);
FORCEPROP 2 LAST ROOM P1V538_BMC_STBY_VR
J 0
(6275 875);
DISPLAY 0.872340 (6275 875);
PAINT GREEN (6275 875);
DISPLAY INVISIBLE (6275 875);
FORCEADD W_VCC_CIRCLE..1
(11300 1900);
FORCEPROP 3 LASTPIN (11300 1900) SIG_NAME P2V5_AUX_BMC\g
J 0
(11310 1910);
DISPLAY 0.659574 (11310 1910);
PAINT MONO (11310 1910);
DISPLAY INVISIBLE (11310 1910);
FORCEPROP 1 LAST HDL_POWER P2V5_AUX_BMC
J 1
(11321 1975);
DISPLAY 0.872340 (11321 1975);
PAINT ORANGE (11321 1975);
FORCEPROP 1 LAST BODY_TYPE PLUMBING
J 0
(11312 1894);
DISPLAY 0.340426 (11312 1894);
PAINT GREEN (11312 1894);
DISPLAY INVISIBLE (11312 1894);
FORCEPROP 1 LAST CDS_LMAN_SYM_OUTLINE -100,100,100,-100
J 0
(11300 1900);
DISPLAY 0.468085 (11300 1900);
PAINT GREEN (11300 1900);
DISPLAY INVISIBLE (11300 1900);
FORCEPROP 1 LAST PATH I96
J 0
(11300 1900);
DISPLAY 0.617021 (11300 1900);
PAINT GREEN (11300 1900);
DISPLAY INVISIBLE (11300 1900);
FORCEPROP 2 LAST CDS_LIB w_power
J 0
(11300 1900);
PAINT MONO (11300 1900);
DISPLAY INVISIBLE (11300 1900);
FORCEADD W_VCC_CIRCLE..1
(11725 3975);
FORCEPROP 3 LASTPIN (11725 3975) SIG_NAME P1V2_AUX_BMC\g
J 0
(11735 3985);
DISPLAY 0.659574 (11735 3985);
PAINT MONO (11735 3985);
DISPLAY INVISIBLE (11735 3985);
FORCEPROP 1 LAST HDL_POWER P1V2_AUX_BMC
J 1
(11746 4050);
DISPLAY 0.872340 (11746 4050);
PAINT ORANGE (11746 4050);
FORCEPROP 1 LAST BODY_TYPE PLUMBING
J 0
(11737 3969);
DISPLAY 0.340426 (11737 3969);
PAINT GREEN (11737 3969);
DISPLAY INVISIBLE (11737 3969);
FORCEPROP 2 LAST CDS_LIB w_power
J 0
(11725 3975);
PAINT MONO (11725 3975);
DISPLAY INVISIBLE (11725 3975);
FORCEPROP 1 LAST PATH I97
J 0
(11725 3975);
DISPLAY 0.617021 (11725 3975);
PAINT GREEN (11725 3975);
DISPLAY INVISIBLE (11725 3975);
FORCEPROP 1 LAST CDS_LMAN_SYM_OUTLINE -100,100,100,-100
J 0
(11725 3975);
DISPLAY 0.468085 (11725 3975);
PAINT GREEN (11725 3975);
DISPLAY INVISIBLE (11725 3975);
FORCEADD 5K1R2F-2-GP..1
(10350 3525);
FORCEPROP 1 LAST LOCATION R9F31
J 0
(10375 3605);
DISPLAY 0.617021 (10375 3605);
PAINT GREEN (10375 3605);
FORCEPROP 1 LAST VALUE 5K1R2F-2-GP
J 0
(10375 3550);
DISPLAY 0.617021 (10375 3550);
PAINT GREEN (10375 3550);
FORCEPROP 2 LAST TOLERANCE 1%
J 0
(10375 3450);
DISPLAY 0.638298 (10375 3450);
PAINT GREEN (10375 3450);
FORCEPROP 2 LAST PACK_SIZE 0402
J 0
(10375 3350);
DISPLAY 0.638298 (10375 3350);
PAINT GREEN (10375 3350);
FORCEPROP 2 LAST RATED 1/16W
J 0
(10375 3400);
DISPLAY 0.638298 (10375 3400);
PAINT GREEN (10375 3400);
FORCEPROP 2 LAST ATTRIBUTE 5.1KOHM
J 0
(10375 3500);
DISPLAY 0.638298 (10375 3500);
PAINT GREEN (10375 3500);
FORCEPROP 1 LAST PACK_TYPE SMD-RG
J 0
(10350 3525);
DISPLAY 0.617021 (10350 3525);
PAINT GREEN (10350 3525);
DISPLAY INVISIBLE (10350 3525);
FORCEPROP 1 LAST PART_NUMBER 64.51015.6DL
J 0
(10350 3525);
DISPLAY 0.617021 (10350 3525);
PAINT GREEN (10350 3525);
DISPLAY INVISIBLE (10350 3525);
FORCEPROP 2 LAST CDS_LIB w_hdl
J 0
(10350 3525);
PAINT MONO (10350 3525);
DISPLAY INVISIBLE (10350 3525);
FORCEPROP 1 LAST PATH I98
J 0
(10350 3525);
DISPLAY 0.617021 (10350 3525);
PAINT GREEN (10350 3525);
DISPLAY INVISIBLE (10350 3525);
FORCEPROP 1 LAST CDS_LMAN_SYM_OUTLINE -50,75,50,-75
J 0
(10350 3525);
DISPLAY 0.468085 (10350 3525);
PAINT GREEN (10350 3525);
DISPLAY INVISIBLE (10350 3525);
FORCEADD DNS..2
(6630 1220);
PAINT RED (6630 1220);
FORCEPROP 1 LAST COMMENT_BODY TRUE
R 1
J 0
(6705 995);
DISPLAY 0.872340 (6705 995);
PAINT GREEN (6705 995);
DISPLAY INVISIBLE (6705 995);
FORCEPROP 2 LAST CDS_LIB mstr_misc
J 0
(6630 1220);
PAINT MONO (6630 1220);
DISPLAY INVISIBLE (6630 1220);
FORCEADD CAD_NOTE..1
(6075 4225);
FORCEPROP 0 LAST L1 MUST PLACE
J 0
(5925 4125);
DISPLAY 0.744681 (5925 4125);
PAINT WHITE (5925 4125);
FORCEPROP 0 LAST L2 NEXT TO INPUT PIN
J 0
(5925 4075);
DISPLAY 0.744681 (5925 4075);
PAINT WHITE (5925 4075);
FORCEPROP 2 LAST CDS_LIB mstr_symbols
J 0
(6075 4225);
DISPLAY 1.617021 (6075 4225);
PAINT WHITE (6075 4225);
DISPLAY INVISIBLE (6075 4225);
FORCEPROP 2 LAST ROOM P1V538_BMC_STBY_VR
J 0
(5925 4175);
DISPLAY 1.659574 (5925 4175);
PAINT GREEN (5925 4175);
DISPLAY INVISIBLE (5925 4175);
FORCEPROP 1 LAST COMMENT_BODY TRUE
J 0
(6100 4325);
DISPLAY 2.212766 (6100 4325);
PAINT PEACH (6100 4325);
DISPLAY INVISIBLE (6100 4325);
FORCEADD CAD_NOTE..1
(5900 2150);
FORCEPROP 0 LAST L1 MUST PLACE
J 0
(5750 2050);
DISPLAY 0.744681 (5750 2050);
PAINT WHITE (5750 2050);
FORCEPROP 0 LAST L2 NEXT TO INPUT PIN
J 0
(5750 2000);
DISPLAY 0.744681 (5750 2000);
PAINT WHITE (5750 2000);
FORCEPROP 2 LAST ROOM P1V538_BMC_STBY_VR
J 0
(5750 2100);
DISPLAY 1.659574 (5750 2100);
PAINT GREEN (5750 2100);
DISPLAY INVISIBLE (5750 2100);
FORCEPROP 2 LAST CDS_LIB mstr_symbols
J 0
(5900 2150);
PAINT MONO (5900 2150);
DISPLAY INVISIBLE (5900 2150);
FORCEPROP 1 LAST COMMENT_BODY TRUE
J 0
(5925 2250);
DISPLAY 2.212766 (5925 2250);
PAINT PEACH (5925 2250);
DISPLAY INVISIBLE (5925 2250);
FORCEADD DESIGN_NOTE..1
(11850 4875);
FORCEPROP 1 LAST COMMENT_BODY TRUE
J 0
(11875 4975);
DISPLAY 1.361702 (11875 4975);
PAINT WHITE (11875 4975);
DISPLAY INVISIBLE (11875 4975);
FORCEPROP 2 LAST CDS_LIB mstr_symbols
J 0
(11850 4875);
PAINT ORANGE (11850 4875);
DISPLAY INVISIBLE (11850 4875);
FORCEADD DESIGN_NOTE..1
(11450 2650);
FORCEPROP 1 LAST COMMENT_BODY TRUE
J 0
(11475 2750);
DISPLAY 1.361702 (11475 2750);
PAINT WHITE (11475 2750);
DISPLAY INVISIBLE (11475 2750);
FORCEPROP 2 LAST CDS_LIB mstr_symbols
J 0
(11450 2650);
PAINT MONO (11450 2650);
DISPLAY INVISIBLE (11450 2650);
FORCEADD DNS..2
(7055 3295);
PAINT RED (7055 3295);
FORCEPROP 1 LAST COMMENT_BODY TRUE
R 1
J 0
(7130 3070);
DISPLAY 0.872340 (7130 3070);
PAINT GREEN (7130 3070);
DISPLAY INVISIBLE (7130 3070);
FORCEPROP 2 LAST CDS_LIB mstr_misc
J 0
(7055 3295);
PAINT ORANGE (7055 3295);
DISPLAY INVISIBLE (7055 3295);
FORCEADD INTEL_CORP_BPAGE..1
(13000 200);
FORCEPROP 1 LAST CDS_CON_LAST_MODIFIED Fri Jun 16 17:49:25 2017
J 0
(11575 525);
PAINT ORANGE (11575 525);
DISPLAY INVISIBLE (11575 525);
FORCEPROP 1 LAST CUSTOM_TXT_CDS <CURRENT_DESIGN_SHEET> OF <TOTAL_DESIGN_SHEETS>
J 0
(12500 225);
PAINT ORANGE (12500 225);
FORCEPROP 1 LAST CUSTOM_TXT_CDS <CON_LAST_MODIFIED>
J 0
(9000 300);
PAINT ORANGE (9000 300);
FORCEPROP 2 LAST CUSTOM_TXT_CDS <XR_PAGE_TITLE>
J 0
(5110 5450);
DISPLAY 0.638298 (5110 5450);
PAINT PINK (5110 5450);
DISPLAY INVISIBLE (5110 5450);
FORCEPROP 1 LAST SCH_TITLE P1V2 & P2V5 BMC STBY VR
J 0
(5050 250);
DISPLAY 1.212766 (5050 250);
PAINT ORANGE (5050 250);
FORCEPROP 1 LAST COMMENT_BODY TRUE
J 0
(13012 212);
DISPLAY 0.446809 (13012 212);
PAINT GREEN (13012 212);
DISPLAY INVISIBLE (13012 212);
FORCEPROP 2 LAST PAGE_BORDER TRUE
J 0
(5110 5450);
DISPLAY 0.851064 (5110 5450);
PAINT PINK (5110 5450);
DISPLAY INVISIBLE (5110 5450);
FORCEPROP 2 LAST CDS_LIB mstr_symbols
J 0
(13000 200);
PAINT MONO (13000 200);
DISPLAY INVISIBLE (13000 200);
FORCEPROP 2 LAST CDS_XR_PAGE_TITLE CR-239 : @BASEBOARD_FAB2_LIB.BASEBOARD_FAB2(SCH_1):PAGE239
J 0
(5110 5450);
DISPLAY 0.638298 (5110 5450);
PAINT PINK (5110 5450);
DISPLAY INVISIBLE (5110 5450);
WIRE 16 -1 (6550 4150)(6550 4075);
WIRE 16 -1 (10350 2975)(10350 2950);
WIRE 16 -1 (9625 4950)(9625 4625);
WIRE 16 -1 (7050 3200)(7050 2925);
WIRE 16 -1 (5750 3900)(5750 4050);
WIRE 16 -1 (10375 4025)(10375 4050);
WIRE 16 -1 (9450 3400)(9450 3475);
WIRE 16 -1 (9350 3475)(9450 3475);
WIRE 16 -1 (5750 4575)(5750 4425);
WIRE 16 -1 (5750 4425)(6550 4425);
WIRE 16 -1 (5750 4425)(5750 4250);
WIRE 16 -1 (6550 4425)(7475 4425);
WIRE 16 -1 (6550 4425)(6550 4350);
WIRE 16 -1 (7475 4425)(8050 4425);
WIRE 16 -1 (7475 4225)(7475 4425);
WIRE 16 -1 (8050 4425)(8050 3975);
WIRE 16 -1 (8050 3975)(8050 3825);
WIRE 16 -1 (8050 3975)(8350 3975);
WIRE 16 -1 (8225 3825)(8050 3825);
WIRE 16 -1 (8225 3775)(8225 3825);
WIRE 16 -1 (8350 3825)(8225 3825);
WIRE 16 -1 (8225 3725)(8225 3775);
WIRE 16 -1 (8350 3775)(8225 3775);
WIRE 16 -1 (8350 3725)(8225 3725);
WIRE 16 -1 (7475 4025)(7475 3900);
WIRE 16 -1 (7250 1975)(7250 1850);
WIRE 16 -1 (5575 2500)(5575 2350);
WIRE 16 -1 (5575 2350)(7250 2350);
WIRE 16 -1 (5575 2350)(5575 2175);
WIRE 16 -1 (7250 2350)(7625 2350);
WIRE 16 -1 (7250 2175)(7250 2350);
WIRE 16 -1 (7625 2350)(7625 1900);
WIRE 16 -1 (7625 1900)(7625 1750);
WIRE 16 -1 (7625 1900)(7925 1900);
WIRE 16 -1 (7800 1750)(7625 1750);
WIRE 16 -1 (7800 1700)(7800 1750);
WIRE 16 -1 (7925 1750)(7800 1750);
WIRE 16 -1 (7800 1650)(7800 1700);
WIRE 16 -1 (7925 1700)(7800 1700);
WIRE 16 -1 (7925 1650)(7800 1650);
WIRE 16 -1 (9200 2650)(9200 2550);
WIRE 16 -1 (11300 1225)(11300 1250);
WIRE 16 -1 (11300 1250)(10450 1250);
WIRE 16 -1 (11300 1400)(11300 1250);
WIRE 16 -1 (10450 1250)(10450 1400);
WIRE 16 -1 (9950 1950)(9950 1975);
WIRE 16 -1 (9925 700)(9925 675);
WIRE 16 -1 (9025 1325)(9025 1400);
WIRE 16 -1 (8925 1400)(9025 1400);
WIRE 16 -1 (11725 3275)(11725 3325);
WIRE 16 -1 (11250 3325)(11725 3325);
WIRE 16 -1 (11725 3475)(11725 3325);
WIRE 16 -1 (10875 3325)(11250 3325);
WIRE 16 -1 (11250 3550)(11250 3325);
WIRE 16 -1 (10875 3325)(10875 3525);
WIRE 16 -1 (5575 1825)(5575 1975);
WIRE 16 -1 (6625 1125)(6625 850);
WIRE 16 -1 (11300 1900)(11300 1750);
WIRE 16 -1 (11300 1750)(10450 1750);
WIRE 16 -1 (11300 1600)(11300 1750);
WIRE 16 -1 (9925 1750)(10450 1750);
WIRE 16 -1 (10450 1750)(10450 1600);
WIRE 16 -1 (9000 1750)(9925 1750);
WIRE 16 -1 (9925 1450)(9925 1750);
WIRE 16 -1 (9000 1700)(9000 1750);
WIRE 16 -1 (8925 1750)(9000 1750);
WIRE 16 -1 (9000 1650)(9000 1700);
WIRE 16 -1 (8925 1700)(9000 1700);
WIRE 16 -1 (8925 1650)(9000 1650);
WIRE 16 -1 (11725 3975)(11725 3825);
WIRE 16 -1 (11250 3825)(11725 3825);
WIRE 16 -1 (11725 3675)(11725 3825);
WIRE 16 -1 (10875 3825)(11250 3825);
FORCEPROP 0 LAST VOLTAGE 1.5
J 0
(11125 3875);
PAINT SKYBLUE (11125 3875);
DISPLAY INVISIBLE (11125 3875);
WIRE 16 -1 (11250 3825)(11250 3750);
WIRE 16 -1 (10350 3825)(10875 3825);
WIRE 16 -1 (10875 3825)(10875 3725);
WIRE 16 -1 (9425 3825)(10350 3825);
WIRE 16 -1 (10350 3650)(10350 3825);
WIRE 16 -1 (9425 3775)(9425 3825);
WIRE 16 -1 (9350 3825)(9425 3825);
WIRE 16 -1 (9425 3725)(9425 3775);
WIRE 16 -1 (9350 3775)(9425 3775);
WIRE 16 -1 (9350 3725)(9425 3725);
WIRE 16 -1 (10350 3175)(10350 3325);
WIRE 16 -1 (10350 3325)(10350 3400);
WIRE 16 -1 (10075 3325)(10350 3325);
WIRE 16 -1 (9350 3575)(10075 3575);
FORCEPROP 2 LAST SIG_NAME VR_P1V2_BMC_STBY_FB
J 0
(9541 3585);
DISPLAY 0.617021 (9541 3585);
PAINT ORANGE (9541 3585);
FORCEPROP 2 LASTPROP $XRERR UNIQUE?
J 0
(9301 3585);
DISPLAY 0.638298 (9301 3585);
PAINT MONO (9301 3585);
DISPLAY INVISIBLE (9301 3585);
WIRE 16 -1 (10075 3575)(10075 3325);
WIRE 16 -1 (6000 1500)(6625 1500);
FORCEPROP 2 LAST SIG_NAME PWRGD_P3V3_STBY
J 0
(6040 1510);
DISPLAY 0.617021 (6040 1510);
PAINT ORANGE (6040 1510);
WIRE 16 -1 (6625 1500)(7925 1500);
WIRE 16 -1 (6625 1325)(6625 1500);
WIRE 3 682 (10750 1700)(10750 1300);
WIRE 3 682 (11150 1700)(10750 1700);
WIRE 3 682 (10750 1300)(11150 1300);
WIRE 3 682 (11150 1300)(11150 1700);
WIRE 3 2175 (5275 525)(11975 525);
WIRE 3 2175 (11975 2825)(11975 525);
WIRE 3 2175 (5275 2825)(5275 525);
WIRE 3 2175 (5275 2825)(11975 2825);
WIRE 3 682 (6325 1850)(6975 1850);
WIRE 3 682 (6325 2400)(6325 1850);
WIRE 3 682 (6975 1850)(6975 2400);
WIRE 3 682 (6975 2400)(6325 2400);
WIRE 3 2175 (6100 3775)(7200 3775);
WIRE 3 2175 (7200 3775)(7200 3450);
WIRE 3 2175 (6100 3775)(6100 3450);
WIRE 3 2175 (6100 3450)(7200 3450);
WIRE 16 -1 (11075 2200)(10375 2200);
FORCEPROP 2 LAST SIG_NAME PWRGD_P2V5_BMC_STBY
J 0
(10466 2210);
DISPLAY 0.617021 (10466 2210);
PAINT ORANGE (10466 2210);
WIRE 3 2175 (11200 3375)(11550 3375);
WIRE 3 2175 (11550 3800)(11550 3375);
WIRE 3 2175 (11200 3800)(11200 3375);
WIRE 3 2175 (11200 3800)(11550 3800);
WIRE 16 -1 (9350 3975)(9625 3975);
WIRE 16 -1 (9625 3975)(9625 4275);
WIRE 16 -1 (9625 4425)(9625 4275);
WIRE 16 -1 (10375 4275)(9625 4275);
FORCEPROP 2 LAST SIG_NAME PWRGD_P1V2_BMC_STBY_R
J 0
(9741 4285);
DISPLAY 0.617021 (9741 4285);
PAINT ORANGE (9741 4285);
FORCEPROP 2 LASTPROP $XRERR UNIQUE?
J 0
(9501 4285);
DISPLAY 0.638298 (9501 4285);
PAINT MONO (9501 4285);
DISPLAY INVISIBLE (9501 4285);
WIRE 16 -1 (10375 4250)(10375 4275);
WIRE 16 -1 (10600 4275)(10375 4275);
WIRE 3 682 (6500 3950)(7150 3950);
WIRE 3 682 (6500 4500)(6500 3950);
WIRE 3 682 (7150 3950)(7150 4500);
WIRE 3 682 (7150 4500)(6500 4500);
WIRE 16 -1 (7050 3400)(7050 3575);
WIRE 16 -1 (7050 3575)(8350 3575);
WIRE 16 -1 (6425 3575)(7050 3575);
FORCEPROP 2 LAST SIG_NAME PWRGD_P2V5_BMC_STBY
J 0
(6516 3585);
DISPLAY 0.617021 (6516 3585);
PAINT ORANGE (6516 3585);
WIRE 16 -1 (8925 1900)(9200 1900);
WIRE 16 -1 (9200 1900)(9200 2200);
WIRE 16 -1 (9200 2350)(9200 2200);
WIRE 16 -1 (9950 2200)(9200 2200);
FORCEPROP 2 LAST SIG_NAME PWRGD_P2V5_BMC_STBY_R
J 0
(9341 2210);
DISPLAY 0.617021 (9341 2210);
PAINT ORANGE (9341 2210);
FORCEPROP 2 LASTPROP $XRERR UNIQUE?
J 0
(9101 2210);
DISPLAY 0.638298 (9101 2210);
PAINT MONO (9101 2210);
DISPLAY INVISIBLE (9101 2210);
WIRE 16 -1 (9950 2175)(9950 2200);
WIRE 16 -1 (10175 2200)(9950 2200);
WIRE 3 2175 (9625 1025)(10300 1025);
WIRE 3 2175 (10300 1600)(10300 1025);
WIRE 3 2175 (9625 1600)(9625 1025);
WIRE 3 2175 (9625 1600)(10300 1600);
WIRE 16 -1 (9925 900)(9925 1100);
WIRE 16 -1 (9925 1100)(9925 1200);
WIRE 16 -1 (9650 1100)(9925 1100);
WIRE 16 -1 (9650 1500)(9650 1100);
WIRE 16 -1 (8925 1500)(9650 1500);
FORCEPROP 2 LAST SIG_NAME VR_P2V5_BMC_STBY_FB
J 0
(9091 1510);
DISPLAY 0.617021 (9091 1510);
PAINT ORANGE (9091 1510);
FORCEPROP 2 LASTPROP $XRERR UNIQUE?
J 0
(8851 1510);
DISPLAY 0.638298 (8851 1510);
PAINT MONO (8851 1510);
DISPLAY INVISIBLE (8851 1510);
WIRE 3 2175 (11500 3950)(12050 3950);
WIRE 3 2175 (12050 4100)(12050 3950);
WIRE 3 2175 (11500 4100)(11500 3950);
WIRE 3 2175 (11500 4100)(12050 4100);
WIRE 3 2175 (10800 3375)(11150 3375);
WIRE 3 2175 (11150 3800)(11150 3375);
WIRE 3 2175 (10800 3800)(10800 3375);
WIRE 3 2175 (10800 3800)(11150 3800);
WIRE 16 -1 (11500 4275)(10800 4275);
FORCEPROP 2 LAST SIG_NAME PWRGD_P1V2_BMC_STBY
J 0
(10866 4285);
DISPLAY 0.617021 (10866 4285);
PAINT ORANGE (10866 4285);
WIRE 3 682 (10600 2875)(10250 2875);
WIRE 3 682 (10600 3250)(10600 2875);
WIRE 3 682 (10250 2875)(10250 3250);
WIRE 3 682 (10250 3250)(10600 3250);
WIRE 3 682 (9825 600)(9825 950);
WIRE 3 682 (10150 600)(9825 600);
WIRE 3 682 (10150 950)(9825 950);
WIRE 3 682 (10150 950)(10150 600);
DOT 1 (11300 1750);
DOT 1 (7625 1900);
DOT 1 (10450 1750);
DOT 1 (11725 3825);
DOT 1 (7800 1750);
DOT 1 (11300 1250);
DOT 1 (11250 3325);
DOT 1 (11250 3825);
DOT 1 (11725 3325);
DOT 1 (8225 3825);
DOT 1 (9925 1100);
DOT 1 (10875 3825);
DOT 1 (10350 3325);
DOT 1 (9950 2200);
DOT 1 (9200 2200);
DOT 1 (6625 1500);
DOT 1 (7050 3575);
DOT 1 (8050 3975);
DOT 1 (7475 4425);
DOT 1 (8225 3775);
DOT 1 (9425 3775);
DOT 1 (9425 3825);
DOT 1 (9625 4275);
DOT 1 (10375 4275);
DOT 1 (7800 1700);
DOT 1 (9000 1700);
DOT 1 (9000 1750);
DOT 1 (10350 3825);
DOT 1 (9925 1750);
DOT 1 (6550 4425);
DOT 1 (5575 2350);
DOT 1 (7250 2350);
DOT 1 (5750 4425);
FORCENOTE
TP FAB3 DELETE C9W22 1101
(10750 1775) 0;
DISPLAY LEFT (10750 1775);
DISPLAY 0.638298 (10750 1775);
PAINT RED (10750 1775);
FORCENOTE
TP FAB3 RESERVE C9W22 1031
(10750 1825) 0;
DISPLAY LEFT (10750 1825);
DISPLAY 0.638298 (10750 1825);
PAINT RED (10750 1825);
FORCENOTE
TP FAB3 RESERVE C9W20 1031
(6325 1800) 0;
DISPLAY LEFT (6325 1800);
DISPLAY 0.638298 (6325 1800);
PAINT RED (6325 1800);
FORCENOTE
TP FAB3 DELETE C9W20 1101
(6325 1750) 0;
DISPLAY LEFT (6325 1750);
DISPLAY 0.638298 (6325 1750);
PAINT RED (6325 1750);
FORCENOTE
IOUT=0.2A
(11275 2400) 0;
DISPLAY LEFT (11275 2400);
DISPLAY 1.021277 (11275 2400);
PAINT PURPLE (11275 2400);
FORCENOTE
TP FAB1 CHANGE PWRGD FROM P2V5 1204
(5375 3300) 0;
DISPLAY LEFT (5375 3300);
DISPLAY 1.021277 (5375 3300);
PAINT RED (5375 3300);
FORCENOTE
TP FAB1 CHANGE RES 0429
(10675 2900) 0;
DISPLAY LEFT (10675 2900);
DISPLAY 1.021277 (10675 2900);
PAINT RED (10675 2900);
FORCENOTE
TP FAB3 RESERVE CAP 1031
(11150 3850) 0;
DISPLAY LEFT (11150 3850);
DISPLAY 0.638298 (11150 3850);
PAINT RED (11150 3850);
FORCENOTE
TP FAB3 RESERVE CAP 1031
(6500 3900) 0;
DISPLAY LEFT (6500 3900);
DISPLAY 0.638298 (6500 3900);
PAINT RED (6500 3900);
FORCENOTE
TP FAB1 R9W31 CHANGE TO 21.5K 1123
(10175 925) 0;
DISPLAY LEFT (10175 925);
DISPLAY 1.021277 (10175 925);
PAINT RED (10175 925);
FORCENOTE
TP FAB1 ADD P2V5 FOR DDR4 1120
(9675 2725) 0;
DISPLAY LEFT (9675 2725);
DISPLAY 1.021277 (9675 2725);
PAINT RED (9675 2725);
FORCENOTE
TP FAB1 CHANGE POWER RAIL 1120
(11500 4125) 0;
DISPLAY LEFT (11500 4125);
DISPLAY 0.638298 (11500 4125);
PAINT RED (11500 4125);
FORCENOTE
TP FAB1 CHANGE RES 0429
(10175 600) 0;
DISPLAY LEFT (10175 600);
DISPLAY 1.021277 (10175 600);
PAINT RED (10175 600);
FORCENOTE
TP FAB1 CHANGE VALUE FOR 1.2V
(8950 3225) 0;
DISPLAY LEFT (8950 3225);
DISPLAY 1.021277 (8950 3225);
PAINT RED (8950 3225);
FORCENOTE
VOUT=2.5V
(11250 2475) 0;
DISPLAY LEFT (11250 2475);
DISPLAY 1.021277 (11250 2475);
PAINT PURPLE (11250 2475);
FORCENOTE
IOUT=0.5A
(11650 4650) 0;
DISPLAY LEFT (11650 4650);
DISPLAY 1.021277 (11650 4650);
PAINT PURPLE (11650 4650);
FORCENOTE
VOUT=1.2V
(11650 4725) 0;
DISPLAY LEFT (11650 4725);
DISPLAY 1.021277 (11650 4725);
PAINT PURPLE (11650 4725);
QUIT
